FILE_TYPE = MACRO_DRAWING;
SET COLOR_WIRE YELLOW;
SET COLOR_PROP ORANGE;
SET COLOR_DOT WHITE;
SET COLOR_ARC YELLOW;
SET COLOR_BODY GREEN;
SET COLOR_NOTE PURPLE;
SET PROP_DISPLAY VALUE;
SET PAGE_NUMBER P72;
FORCEADD UNIVERSAL_GND..1
(-2800 -750);
FORCEPROP 3 LASTPIN (-2800 -700) SIG_NAME GND\g
J 0
(-2790 -690);
DISPLAY 0.659574 (-2790 -690);
PAINT MONO (-2790 -690);
DISPLAY INVISIBLE (-2790 -690);
FORCEPROP 2 LAST CDS_LIB logical_power
J 0
(-2800 -750);
PAINT MONO (-2800 -750);
DISPLAY INVISIBLE (-2800 -750);
FORCEPROP 1 LAST HDL_POWER GND
J 1
(-2775 -825);
DISPLAY 0.872340 (-2775 -825);
PAINT GREEN (-2775 -825);
DISPLAY INVISIBLE (-2775 -825);
FORCEPROP 1 LAST PATH I1
J 0
(-2725 -750);
DISPLAY 0.872340 (-2725 -750);
PAINT AQUA (-2725 -750);
DISPLAY INVISIBLE (-2725 -750);
FORCEADD SOCKET4677_AZIF0045P001C01CS..37
(-1350 1775);
FORCEPROP 1 LAST PART_NUMBER DGA^7000023
J 0
(-2400 4025);
DISPLAY 0.723404 (-2400 4025);
PAINT GREEN (-2400 4025);
DISPLAY INVISIBLE (-2400 4025);
FORCEPROP 2 LAST PART_TYPE SMLF
J 0
(-2400 4200);
DISPLAY 1.021277 (-2400 4200);
FORCEPROP 1 LAST MATERIAL IO
J 0
(-2400 3950);
DISPLAY 0.723404 (-2400 3950);
PAINT GREEN (-2400 3950);
FORCEPROP 2 LAST VALUE SOCKET4677_AZIF0045-P001C01CS
J 0
(-2400 4150);
DISPLAY 1.021277 (-2400 4150);
FORCEPROP 1 LAST $LOCATION U1
J 0
(-2400 4100);
DISPLAY 0.723404 (-2400 4100);
PAINT GREEN (-2400 4100);
FORCEPROP 0 LASTPIN (-2550 3400) $PN BR5
J 2
(-2560 3410);
DISPLAY 0.680851 (-2560 3410);
PAINT MONO (-2560 3410);
FORCEPROP 0 LASTPIN (-150 -200) $PN AW21
J 0
(-140 -190);
DISPLAY 0.680851 (-140 -190);
PAINT MONO (-140 -190);
FORCEPROP 0 LASTPIN (-150 -150) $PN AW23
J 0
(-140 -140);
DISPLAY 0.680851 (-140 -140);
PAINT MONO (-140 -140);
FORCEPROP 0 LASTPIN (-150 -100) $PN AW25
J 0
(-140 -90);
DISPLAY 0.680851 (-140 -90);
PAINT MONO (-140 -90);
FORCEPROP 0 LASTPIN (-150 -50) $PN AW62
J 0
(-140 -40);
DISPLAY 0.680851 (-140 -40);
PAINT MONO (-140 -40);
FORCEPROP 0 LASTPIN (-150 0) $PN AW66
J 0
(-140 10);
DISPLAY 0.680851 (-140 10);
PAINT MONO (-140 10);
FORCEPROP 0 LASTPIN (-150 50) $PN AW68
J 0
(-140 60);
DISPLAY 0.680851 (-140 60);
PAINT MONO (-140 60);
FORCEPROP 0 LASTPIN (-150 100) $PN AW72
J 0
(-140 110);
DISPLAY 0.680851 (-140 110);
PAINT MONO (-140 110);
FORCEPROP 0 LASTPIN (-150 150) $PN AW80
J 0
(-140 160);
DISPLAY 0.680851 (-140 160);
PAINT MONO (-140 160);
FORCEPROP 0 LASTPIN (-150 200) $PN AW82
J 0
(-140 210);
DISPLAY 0.680851 (-140 210);
PAINT MONO (-140 210);
FORCEPROP 0 LASTPIN (-150 250) $PN AW84
J 0
(-140 260);
DISPLAY 0.680851 (-140 260);
PAINT MONO (-140 260);
FORCEPROP 0 LASTPIN (-150 300) $PN AW88
J 0
(-140 310);
DISPLAY 0.680851 (-140 310);
PAINT MONO (-140 310);
FORCEPROP 0 LASTPIN (-150 450) $PN AY12
J 0
(-140 460);
DISPLAY 0.680851 (-140 460);
PAINT MONO (-140 460);
FORCEPROP 0 LASTPIN (-150 500) $PN AY16
J 0
(-140 510);
DISPLAY 0.680851 (-140 510);
PAINT MONO (-140 510);
FORCEPROP 0 LASTPIN (-150 350) $PN AY4
J 0
(-140 360);
DISPLAY 0.680851 (-140 360);
PAINT MONO (-140 360);
FORCEPROP 0 LASTPIN (-150 550) $PN AY71
J 0
(-140 560);
DISPLAY 0.680851 (-140 560);
PAINT MONO (-140 560);
FORCEPROP 0 LASTPIN (-150 600) $PN AY77
J 0
(-140 610);
DISPLAY 0.680851 (-140 610);
PAINT MONO (-140 610);
FORCEPROP 0 LASTPIN (-150 650) $PN AY79
J 0
(-140 660);
DISPLAY 0.680851 (-140 660);
PAINT MONO (-140 660);
FORCEPROP 0 LASTPIN (-150 400) $PN AY8
J 0
(-140 410);
DISPLAY 0.680851 (-140 410);
PAINT MONO (-140 410);
FORCEPROP 0 LASTPIN (-150 700) $PN AY81
J 0
(-140 710);
DISPLAY 0.680851 (-140 710);
PAINT MONO (-140 710);
FORCEPROP 0 LASTPIN (-150 750) $PN AY83
J 0
(-140 760);
DISPLAY 0.680851 (-140 760);
PAINT MONO (-140 760);
FORCEPROP 0 LASTPIN (-150 800) $PN BA17
J 0
(-140 810);
DISPLAY 0.680851 (-140 810);
PAINT MONO (-140 810);
FORCEPROP 0 LASTPIN (-150 850) $PN BA60
J 0
(-140 860);
DISPLAY 0.680851 (-140 860);
PAINT MONO (-140 860);
FORCEPROP 0 LASTPIN (-150 900) $PN BA64
J 0
(-140 910);
DISPLAY 0.680851 (-140 910);
PAINT MONO (-140 910);
FORCEPROP 0 LASTPIN (-150 950) $PN BA74
J 0
(-140 960);
DISPLAY 0.680851 (-140 960);
PAINT MONO (-140 960);
FORCEPROP 0 LASTPIN (-150 1000) $PN BA84
J 0
(-140 1010);
DISPLAY 0.680851 (-140 1010);
PAINT MONO (-140 1010);
FORCEPROP 0 LASTPIN (-150 1050) $PN BA88
J 0
(-140 1060);
DISPLAY 0.680851 (-140 1060);
PAINT MONO (-140 1060);
FORCEPROP 0 LASTPIN (-150 1200) $PN BB10
J 0
(-140 1210);
DISPLAY 0.680851 (-140 1210);
PAINT MONO (-140 1210);
FORCEPROP 0 LASTPIN (-150 1250) $PN BB12
J 0
(-140 1260);
DISPLAY 0.680851 (-140 1260);
PAINT MONO (-140 1260);
FORCEPROP 0 LASTPIN (-150 1300) $PN BB16
J 0
(-140 1310);
DISPLAY 0.680851 (-140 1310);
PAINT MONO (-140 1310);
FORCEPROP 0 LASTPIN (-150 1350) $PN BB20
J 0
(-140 1360);
DISPLAY 0.680851 (-140 1360);
PAINT MONO (-140 1360);
FORCEPROP 0 LASTPIN (-150 1400) $PN BB22
J 0
(-140 1410);
DISPLAY 0.680851 (-140 1410);
PAINT MONO (-140 1410);
FORCEPROP 0 LASTPIN (-150 1450) $PN BB24
J 0
(-140 1460);
DISPLAY 0.680851 (-140 1460);
PAINT MONO (-140 1460);
FORCEPROP 0 LASTPIN (-150 1500) $PN BB26
J 0
(-140 1510);
DISPLAY 0.680851 (-140 1510);
PAINT MONO (-140 1510);
FORCEPROP 0 LASTPIN (-150 1100) $PN BB4
J 0
(-140 1110);
DISPLAY 0.680851 (-140 1110);
PAINT MONO (-140 1110);
FORCEPROP 0 LASTPIN (-150 1550) $PN BB63
J 0
(-140 1560);
DISPLAY 0.680851 (-140 1560);
PAINT MONO (-140 1560);
FORCEPROP 0 LASTPIN (-150 1600) $PN BB69
J 0
(-140 1610);
DISPLAY 0.680851 (-140 1610);
PAINT MONO (-140 1610);
FORCEPROP 0 LASTPIN (-150 1650) $PN BB71
J 0
(-140 1660);
DISPLAY 0.680851 (-140 1660);
PAINT MONO (-140 1660);
FORCEPROP 0 LASTPIN (-150 1700) $PN BB77
J 0
(-140 1710);
DISPLAY 0.680851 (-140 1710);
PAINT MONO (-140 1710);
FORCEPROP 0 LASTPIN (-150 1750) $PN BB79
J 0
(-140 1760);
DISPLAY 0.680851 (-140 1760);
PAINT MONO (-140 1760);
FORCEPROP 0 LASTPIN (-150 1150) $PN BB8
J 0
(-140 1160);
DISPLAY 0.680851 (-140 1160);
PAINT MONO (-140 1160);
FORCEPROP 0 LASTPIN (-150 1800) $PN BB83
J 0
(-140 1810);
DISPLAY 0.680851 (-140 1810);
PAINT MONO (-140 1810);
FORCEPROP 0 LASTPIN (-150 1850) $PN BB87
J 0
(-140 1860);
DISPLAY 0.680851 (-140 1860);
PAINT MONO (-140 1860);
FORCEPROP 0 LASTPIN (-150 1900) $PN BB91
J 0
(-140 1910);
DISPLAY 0.680851 (-140 1910);
PAINT MONO (-140 1910);
FORCEPROP 0 LASTPIN (-150 1950) $PN BC1
J 0
(-140 1960);
DISPLAY 0.680851 (-140 1960);
PAINT MONO (-140 1960);
FORCEPROP 0 LASTPIN (-150 2100) $PN BC13
J 0
(-140 2110);
DISPLAY 0.680851 (-140 2110);
PAINT MONO (-140 2110);
FORCEPROP 0 LASTPIN (-150 2150) $PN BC17
J 0
(-140 2160);
DISPLAY 0.680851 (-140 2160);
PAINT MONO (-140 2160);
FORCEPROP 0 LASTPIN (-150 2000) $PN BC5
J 0
(-140 2010);
DISPLAY 0.680851 (-140 2010);
PAINT MONO (-140 2010);
FORCEPROP 0 LASTPIN (-150 2200) $PN BC62
J 0
(-140 2210);
DISPLAY 0.680851 (-140 2210);
PAINT MONO (-140 2210);
FORCEPROP 0 LASTPIN (-150 2250) $PN BC66
J 0
(-140 2260);
DISPLAY 0.680851 (-140 2260);
PAINT MONO (-140 2260);
FORCEPROP 0 LASTPIN (-150 2300) $PN BC72
J 0
(-140 2310);
DISPLAY 0.680851 (-140 2310);
PAINT MONO (-140 2310);
FORCEPROP 0 LASTPIN (-150 2350) $PN BC76
J 0
(-140 2360);
DISPLAY 0.680851 (-140 2360);
PAINT MONO (-140 2360);
FORCEPROP 0 LASTPIN (-150 2400) $PN BC78
J 0
(-140 2410);
DISPLAY 0.680851 (-140 2410);
PAINT MONO (-140 2410);
FORCEPROP 0 LASTPIN (-150 2450) $PN BC84
J 0
(-140 2460);
DISPLAY 0.680851 (-140 2460);
PAINT MONO (-140 2460);
FORCEPROP 0 LASTPIN (-150 2500) $PN BC86
J 0
(-140 2510);
DISPLAY 0.680851 (-140 2510);
PAINT MONO (-140 2510);
FORCEPROP 0 LASTPIN (-150 2550) $PN BC88
J 0
(-140 2560);
DISPLAY 0.680851 (-140 2560);
PAINT MONO (-140 2560);
FORCEPROP 0 LASTPIN (-150 2050) $PN BC9
J 0
(-140 2060);
DISPLAY 0.680851 (-140 2060);
PAINT MONO (-140 2060);
FORCEPROP 0 LASTPIN (-150 2700) $PN BD12
J 0
(-140 2710);
DISPLAY 0.680851 (-140 2710);
PAINT MONO (-140 2710);
FORCEPROP 0 LASTPIN (-150 2750) $PN BD16
J 0
(-140 2760);
DISPLAY 0.680851 (-140 2760);
PAINT MONO (-140 2760);
FORCEPROP 0 LASTPIN (-150 2800) $PN BD20
J 0
(-140 2810);
DISPLAY 0.680851 (-140 2810);
PAINT MONO (-140 2810);
FORCEPROP 0 LASTPIN (-150 2600) $PN BD4
J 0
(-140 2610);
DISPLAY 0.680851 (-140 2610);
PAINT MONO (-140 2610);
FORCEPROP 0 LASTPIN (-150 2650) $PN BD8
J 0
(-140 2660);
DISPLAY 0.680851 (-140 2660);
PAINT MONO (-140 2660);
FORCEPROP 0 LASTPIN (-150 2850) $PN BD81
J 0
(-140 2860);
DISPLAY 0.680851 (-140 2860);
PAINT MONO (-140 2860);
FORCEPROP 0 LASTPIN (-150 2900) $PN BD85
J 0
(-140 2910);
DISPLAY 0.680851 (-140 2910);
PAINT MONO (-140 2910);
FORCEPROP 0 LASTPIN (-150 2950) $PN BD89
J 0
(-140 2960);
DISPLAY 0.680851 (-140 2960);
PAINT MONO (-140 2960);
FORCEPROP 0 LASTPIN (-150 3000) $PN BE64
J 0
(-140 3010);
DISPLAY 0.680851 (-140 3010);
PAINT MONO (-140 3010);
FORCEPROP 0 LASTPIN (-150 3050) $PN BE66
J 0
(-140 3060);
DISPLAY 0.680851 (-140 3060);
PAINT MONO (-140 3060);
FORCEPROP 0 LASTPIN (-150 3100) $PN BE68
J 0
(-140 3110);
DISPLAY 0.680851 (-140 3110);
PAINT MONO (-140 3110);
FORCEPROP 0 LASTPIN (-150 3150) $PN BE74
J 0
(-140 3160);
DISPLAY 0.680851 (-140 3160);
PAINT MONO (-140 3160);
FORCEPROP 0 LASTPIN (-150 3200) $PN BE76
J 0
(-140 3210);
DISPLAY 0.680851 (-140 3210);
PAINT MONO (-140 3210);
FORCEPROP 0 LASTPIN (-150 3250) $PN BE78
J 0
(-140 3260);
DISPLAY 0.680851 (-140 3260);
PAINT MONO (-140 3260);
FORCEPROP 0 LASTPIN (-150 3300) $PN BE84
J 0
(-140 3310);
DISPLAY 0.680851 (-140 3310);
PAINT MONO (-140 3310);
FORCEPROP 0 LASTPIN (-150 3450) $PN BF12
J 0
(-140 3460);
DISPLAY 0.680851 (-140 3460);
PAINT MONO (-140 3460);
FORCEPROP 0 LASTPIN (-150 3500) $PN BF16
J 0
(-140 3510);
DISPLAY 0.680851 (-140 3510);
PAINT MONO (-140 3510);
FORCEPROP 0 LASTPIN (-150 3550) $PN BF20
J 0
(-140 3560);
DISPLAY 0.680851 (-140 3560);
PAINT MONO (-140 3560);
FORCEPROP 0 LASTPIN (-150 3350) $PN BF4
J 0
(-140 3360);
DISPLAY 0.680851 (-140 3360);
PAINT MONO (-140 3360);
FORCEPROP 0 LASTPIN (-150 3600) $PN BF61
J 0
(-140 3610);
DISPLAY 0.680851 (-140 3610);
PAINT MONO (-140 3610);
FORCEPROP 0 LASTPIN (-150 3650) $PN BF63
J 0
(-140 3660);
DISPLAY 0.680851 (-140 3660);
PAINT MONO (-140 3660);
FORCEPROP 0 LASTPIN (-150 3700) $PN BF73
J 0
(-140 3710);
DISPLAY 0.680851 (-140 3710);
PAINT MONO (-140 3710);
FORCEPROP 0 LASTPIN (-150 3750) $PN BF75
J 0
(-140 3760);
DISPLAY 0.680851 (-140 3760);
PAINT MONO (-140 3760);
FORCEPROP 0 LASTPIN (-2550 -200) $PN BF79
J 2
(-2560 -190);
DISPLAY 0.680851 (-2560 -190);
PAINT MONO (-2560 -190);
FORCEPROP 0 LASTPIN (-150 3400) $PN BF8
J 0
(-140 3410);
DISPLAY 0.680851 (-140 3410);
PAINT MONO (-140 3410);
FORCEPROP 0 LASTPIN (-2550 -150) $PN BF83
J 2
(-2560 -140);
DISPLAY 0.680851 (-2560 -140);
PAINT MONO (-2560 -140);
FORCEPROP 0 LASTPIN (-2550 -100) $PN BG1
J 2
(-2560 -90);
DISPLAY 0.680851 (-2560 -90);
PAINT MONO (-2560 -90);
FORCEPROP 0 LASTPIN (-2550 50) $PN BG13
J 2
(-2560 60);
DISPLAY 0.680851 (-2560 60);
PAINT MONO (-2560 60);
FORCEPROP 0 LASTPIN (-2550 100) $PN BG17
J 2
(-2560 110);
DISPLAY 0.680851 (-2560 110);
PAINT MONO (-2560 110);
FORCEPROP 0 LASTPIN (-2550 150) $PN BG21
J 2
(-2560 160);
DISPLAY 0.680851 (-2560 160);
PAINT MONO (-2560 160);
FORCEPROP 0 LASTPIN (-2550 200) $PN BG23
J 2
(-2560 210);
DISPLAY 0.680851 (-2560 210);
PAINT MONO (-2560 210);
FORCEPROP 0 LASTPIN (-2550 250) $PN BG25
J 2
(-2560 260);
DISPLAY 0.680851 (-2560 260);
PAINT MONO (-2560 260);
FORCEPROP 0 LASTPIN (-2550 -50) $PN BG5
J 2
(-2560 -40);
DISPLAY 0.680851 (-2560 -40);
PAINT MONO (-2560 -40);
FORCEPROP 0 LASTPIN (-2550 300) $PN BG70
J 2
(-2560 310);
DISPLAY 0.680851 (-2560 310);
PAINT MONO (-2560 310);
FORCEPROP 0 LASTPIN (-2550 0) $PN BG9
J 2
(-2560 10);
DISPLAY 0.680851 (-2560 10);
PAINT MONO (-2560 10);
FORCEPROP 0 LASTPIN (-2550 450) $PN BH12
J 2
(-2560 460);
DISPLAY 0.680851 (-2560 460);
PAINT MONO (-2560 460);
FORCEPROP 0 LASTPIN (-2550 500) $PN BH16
J 2
(-2560 510);
DISPLAY 0.680851 (-2560 510);
PAINT MONO (-2560 510);
FORCEPROP 0 LASTPIN (-2550 550) $PN BH20
J 2
(-2560 560);
DISPLAY 0.680851 (-2560 560);
PAINT MONO (-2560 560);
FORCEPROP 0 LASTPIN (-2550 350) $PN BH4
J 2
(-2560 360);
DISPLAY 0.680851 (-2560 360);
PAINT MONO (-2560 360);
FORCEPROP 0 LASTPIN (-2550 600) $PN BH67
J 2
(-2560 610);
DISPLAY 0.680851 (-2560 610);
PAINT MONO (-2560 610);
FORCEPROP 0 LASTPIN (-2550 650) $PN BH73
J 2
(-2560 660);
DISPLAY 0.680851 (-2560 660);
PAINT MONO (-2560 660);
FORCEPROP 0 LASTPIN (-2550 700) $PN BH77
J 2
(-2560 710);
DISPLAY 0.680851 (-2560 710);
PAINT MONO (-2560 710);
FORCEPROP 0 LASTPIN (-2550 400) $PN BH8
J 2
(-2560 410);
DISPLAY 0.680851 (-2560 410);
PAINT MONO (-2560 410);
FORCEPROP 0 LASTPIN (-2550 750) $PN BH81
J 2
(-2560 760);
DISPLAY 0.680851 (-2560 760);
PAINT MONO (-2560 760);
FORCEPROP 0 LASTPIN (-2550 800) $PN BH83
J 2
(-2560 810);
DISPLAY 0.680851 (-2560 810);
PAINT MONO (-2560 810);
FORCEPROP 0 LASTPIN (-2550 850) $PN BJ62
J 2
(-2560 860);
DISPLAY 0.680851 (-2560 860);
PAINT MONO (-2560 860);
FORCEPROP 0 LASTPIN (-2550 900) $PN BJ68
J 2
(-2560 910);
DISPLAY 0.680851 (-2560 910);
PAINT MONO (-2560 910);
FORCEPROP 0 LASTPIN (-2550 950) $PN BJ80
J 2
(-2560 960);
DISPLAY 0.680851 (-2560 960);
PAINT MONO (-2560 960);
FORCEPROP 0 LASTPIN (-2550 1000) $PN BJ82
J 2
(-2560 1010);
DISPLAY 0.680851 (-2560 1010);
PAINT MONO (-2560 1010);
FORCEPROP 0 LASTPIN (-2550 1050) $PN BJ84
J 2
(-2560 1060);
DISPLAY 0.680851 (-2560 1060);
PAINT MONO (-2560 1060);
FORCEPROP 0 LASTPIN (-2550 1100) $PN BJ86
J 2
(-2560 1110);
DISPLAY 0.680851 (-2560 1110);
PAINT MONO (-2560 1110);
FORCEPROP 0 LASTPIN (-2550 1150) $PN BJ88
J 2
(-2560 1160);
DISPLAY 0.680851 (-2560 1160);
PAINT MONO (-2560 1160);
FORCEPROP 0 LASTPIN (-2550 1200) $PN BJ90
J 2
(-2560 1210);
DISPLAY 0.680851 (-2560 1210);
PAINT MONO (-2560 1210);
FORCEPROP 0 LASTPIN (-2550 1350) $PN BK12
J 2
(-2560 1360);
DISPLAY 0.680851 (-2560 1360);
PAINT MONO (-2560 1360);
FORCEPROP 0 LASTPIN (-2550 1400) $PN BK16
J 2
(-2560 1410);
DISPLAY 0.680851 (-2560 1410);
PAINT MONO (-2560 1410);
FORCEPROP 0 LASTPIN (-2550 1450) $PN BK20
J 2
(-2560 1460);
DISPLAY 0.680851 (-2560 1460);
PAINT MONO (-2560 1460);
FORCEPROP 0 LASTPIN (-2550 1250) $PN BK4
J 2
(-2560 1260);
DISPLAY 0.680851 (-2560 1260);
PAINT MONO (-2560 1260);
FORCEPROP 0 LASTPIN (-2550 1500) $PN BK65
J 2
(-2560 1510);
DISPLAY 0.680851 (-2560 1510);
PAINT MONO (-2560 1510);
FORCEPROP 0 LASTPIN (-2550 1550) $PN BK71
J 2
(-2560 1560);
DISPLAY 0.680851 (-2560 1560);
PAINT MONO (-2560 1560);
FORCEPROP 0 LASTPIN (-2550 1600) $PN BK75
J 2
(-2560 1610);
DISPLAY 0.680851 (-2560 1610);
PAINT MONO (-2560 1610);
FORCEPROP 0 LASTPIN (-2550 1650) $PN BK79
J 2
(-2560 1660);
DISPLAY 0.680851 (-2560 1660);
PAINT MONO (-2560 1660);
FORCEPROP 0 LASTPIN (-2550 1300) $PN BK8
J 2
(-2560 1310);
DISPLAY 0.680851 (-2560 1310);
PAINT MONO (-2560 1310);
FORCEPROP 0 LASTPIN (-2550 1700) $PN BL1
J 2
(-2560 1710);
DISPLAY 0.680851 (-2560 1710);
PAINT MONO (-2560 1710);
FORCEPROP 0 LASTPIN (-2550 1850) $PN BL13
J 2
(-2560 1860);
DISPLAY 0.680851 (-2560 1860);
PAINT MONO (-2560 1860);
FORCEPROP 0 LASTPIN (-2550 1900) $PN BL17
J 2
(-2560 1910);
DISPLAY 0.680851 (-2560 1910);
PAINT MONO (-2560 1910);
FORCEPROP 0 LASTPIN (-2550 1750) $PN BL5
J 2
(-2560 1760);
DISPLAY 0.680851 (-2560 1760);
PAINT MONO (-2560 1760);
FORCEPROP 0 LASTPIN (-2550 1950) $PN BL68
J 2
(-2560 1960);
DISPLAY 0.680851 (-2560 1960);
PAINT MONO (-2560 1960);
FORCEPROP 0 LASTPIN (-2550 2000) $PN BL70
J 2
(-2560 2010);
DISPLAY 0.680851 (-2560 2010);
PAINT MONO (-2560 2010);
FORCEPROP 0 LASTPIN (-2550 2050) $PN BL72
J 2
(-2560 2060);
DISPLAY 0.680851 (-2560 2060);
PAINT MONO (-2560 2060);
FORCEPROP 0 LASTPIN (-2550 2100) $PN BL78
J 2
(-2560 2110);
DISPLAY 0.680851 (-2560 2110);
PAINT MONO (-2560 2110);
FORCEPROP 0 LASTPIN (-2550 1800) $PN BL9
J 2
(-2560 1810);
DISPLAY 0.680851 (-2560 1810);
PAINT MONO (-2560 1810);
FORCEPROP 0 LASTPIN (-2550 2250) $PN BM12
J 2
(-2560 2260);
DISPLAY 0.680851 (-2560 2260);
PAINT MONO (-2560 2260);
FORCEPROP 0 LASTPIN (-2550 2300) $PN BM16
J 2
(-2560 2310);
DISPLAY 0.680851 (-2560 2310);
PAINT MONO (-2560 2310);
FORCEPROP 0 LASTPIN (-2550 2350) $PN BM20
J 2
(-2560 2360);
DISPLAY 0.680851 (-2560 2360);
PAINT MONO (-2560 2360);
FORCEPROP 0 LASTPIN (-2550 2400) $PN BM22
J 2
(-2560 2410);
DISPLAY 0.680851 (-2560 2410);
PAINT MONO (-2560 2410);
FORCEPROP 0 LASTPIN (-2550 2450) $PN BM24
J 2
(-2560 2460);
DISPLAY 0.680851 (-2560 2460);
PAINT MONO (-2560 2460);
FORCEPROP 0 LASTPIN (-2550 2500) $PN BM26
J 2
(-2560 2510);
DISPLAY 0.680851 (-2560 2510);
PAINT MONO (-2560 2510);
FORCEPROP 0 LASTPIN (-2550 2150) $PN BM4
J 2
(-2560 2160);
DISPLAY 0.680851 (-2560 2160);
PAINT MONO (-2560 2160);
FORCEPROP 0 LASTPIN (-2550 2550) $PN BM61
J 2
(-2560 2560);
DISPLAY 0.680851 (-2560 2560);
PAINT MONO (-2560 2560);
FORCEPROP 0 LASTPIN (-2550 2600) $PN BM73
J 2
(-2560 2610);
DISPLAY 0.680851 (-2560 2610);
PAINT MONO (-2560 2610);
FORCEPROP 0 LASTPIN (-2550 2650) $PN BM77
J 2
(-2560 2660);
DISPLAY 0.680851 (-2560 2660);
PAINT MONO (-2560 2660);
FORCEPROP 0 LASTPIN (-2550 2200) $PN BM8
J 2
(-2560 2210);
DISPLAY 0.680851 (-2560 2210);
PAINT MONO (-2560 2210);
FORCEPROP 0 LASTPIN (-2550 2700) $PN BN31
J 2
(-2560 2710);
DISPLAY 0.680851 (-2560 2710);
PAINT MONO (-2560 2710);
FORCEPROP 0 LASTPIN (-2550 2750) $PN BN62
J 2
(-2560 2760);
DISPLAY 0.680851 (-2560 2760);
PAINT MONO (-2560 2760);
FORCEPROP 0 LASTPIN (-2550 2800) $PN BN70
J 2
(-2560 2810);
DISPLAY 0.680851 (-2560 2810);
PAINT MONO (-2560 2810);
FORCEPROP 0 LASTPIN (-2550 3000) $PN BP12
J 2
(-2560 3010);
DISPLAY 0.680851 (-2560 3010);
PAINT MONO (-2560 3010);
FORCEPROP 0 LASTPIN (-2550 3050) $PN BP16
J 2
(-2560 3060);
DISPLAY 0.680851 (-2560 3060);
PAINT MONO (-2560 3060);
FORCEPROP 0 LASTPIN (-2550 2850) $PN BP2
J 2
(-2560 2860);
DISPLAY 0.680851 (-2560 2860);
PAINT MONO (-2560 2860);
FORCEPROP 0 LASTPIN (-2550 3100) $PN BP20
J 2
(-2560 3110);
DISPLAY 0.680851 (-2560 3110);
PAINT MONO (-2560 3110);
FORCEPROP 0 LASTPIN (-2550 2900) $PN BP4
J 2
(-2560 2910);
DISPLAY 0.680851 (-2560 2910);
PAINT MONO (-2560 2910);
FORCEPROP 0 LASTPIN (-2550 3150) $PN BP63
J 2
(-2560 3160);
DISPLAY 0.680851 (-2560 3160);
PAINT MONO (-2560 3160);
FORCEPROP 0 LASTPIN (-2550 3200) $PN BP71
J 2
(-2560 3210);
DISPLAY 0.680851 (-2560 3210);
PAINT MONO (-2560 3210);
FORCEPROP 0 LASTPIN (-2550 3250) $PN BP73
J 2
(-2560 3260);
DISPLAY 0.680851 (-2560 3260);
PAINT MONO (-2560 3260);
FORCEPROP 0 LASTPIN (-2550 3300) $PN BP75
J 2
(-2560 3310);
DISPLAY 0.680851 (-2560 3310);
PAINT MONO (-2560 3310);
FORCEPROP 0 LASTPIN (-2550 3350) $PN BP77
J 2
(-2560 3360);
DISPLAY 0.680851 (-2560 3360);
PAINT MONO (-2560 3360);
FORCEPROP 0 LASTPIN (-2550 2950) $PN BP8
J 2
(-2560 2960);
DISPLAY 0.680851 (-2560 2960);
PAINT MONO (-2560 2960);
FORCEPROP 0 LASTPIN (-2550 3500) $PN BR13
J 2
(-2560 3510);
DISPLAY 0.680851 (-2560 3510);
PAINT MONO (-2560 3510);
FORCEPROP 0 LASTPIN (-2550 3550) $PN BR17
J 2
(-2560 3560);
DISPLAY 0.680851 (-2560 3560);
PAINT MONO (-2560 3560);
FORCEPROP 0 LASTPIN (-2550 3600) $PN BR27
J 2
(-2560 3610);
DISPLAY 0.680851 (-2560 3610);
PAINT MONO (-2560 3610);
FORCEPROP 0 LASTPIN (-2550 3650) $PN BR29
J 2
(-2560 3660);
DISPLAY 0.680851 (-2560 3660);
PAINT MONO (-2560 3660);
FORCEPROP 0 LASTPIN (-2550 3700) $PN BR31
J 2
(-2560 3710);
DISPLAY 0.680851 (-2560 3710);
PAINT MONO (-2560 3710);
FORCEPROP 0 LASTPIN (-2550 3750) $PN BR33
J 2
(-2560 3760);
DISPLAY 0.680851 (-2560 3760);
PAINT MONO (-2560 3760);
FORCEPROP 0 LASTPIN (-2550 3450) $PN BR9
J 2
(-2560 3460);
DISPLAY 0.680851 (-2560 3460);
PAINT MONO (-2560 3460);
FORCEPROP 2 LAST CDS_LIB pure_quanta
J 0
(-1350 1775);
DISPLAY INVISIBLE (-1350 1775);
FORCEPROP 1 LAST NEEDS_NO_SIZE TRUE
J 0
(-1350 1775);
DISPLAY 0.723404 (-1350 1775);
PAINT GREEN (-1350 1775);
DISPLAY INVISIBLE (-1350 1775);
FORCEPROP 1 LAST CDS_LMAN_SYM_OUTLINE -1050,2150,1050,-2100
J 0
(-1350 1775);
DISPLAY 0.468085 (-1350 1775);
PAINT GREEN (-1350 1775);
DISPLAY INVISIBLE (-1350 1775);
FORCEPROP 0 LAST CDS_LOCATION U1
J 0
(-2400 4250);
DISPLAY 1.021277 (-2400 4250);
DISPLAY INVISIBLE (-2400 4250);
FORCEPROP 0 LAST $SEC 37
J 0
(-2400 4250);
DISPLAY 0.680851 (-2400 4250);
PAINT MONO (-2400 4250);
DISPLAY INVISIBLE (-2400 4250);
FORCEPROP 2 LAST CDS_SEC 37
J 0
(-2400 4250);
DISPLAY 1.021277 (-2400 4250);
DISPLAY INVISIBLE (-2400 4250);
FORCEPROP 1 LAST PATH I2
J 0
(-1350 1775);
DISPLAY 0.723404 (-1350 1775);
PAINT GREEN (-1350 1775);
DISPLAY INVISIBLE (-1350 1775);
FORCEADD UNIVERSAL_GND..1
(100 -750);
FORCEPROP 3 LASTPIN (100 -700) SIG_NAME GND\g
J 0
(110 -690);
DISPLAY 0.659574 (110 -690);
PAINT MONO (110 -690);
DISPLAY INVISIBLE (110 -690);
FORCEPROP 2 LAST CDS_LIB logical_power
J 0
(100 -750);
PAINT MONO (100 -750);
DISPLAY INVISIBLE (100 -750);
FORCEPROP 1 LAST HDL_POWER GND
J 1
(125 -825);
DISPLAY 0.872340 (125 -825);
PAINT GREEN (125 -825);
DISPLAY INVISIBLE (125 -825);
FORCEPROP 1 LAST PATH I3
J 0
(175 -750);
DISPLAY 0.872340 (175 -750);
PAINT AQUA (175 -750);
DISPLAY INVISIBLE (175 -750);
FORCEADD UNIVERSAL_GND..1
(250 -750);
FORCEPROP 3 LASTPIN (250 -700) SIG_NAME GND\g
J 0
(260 -690);
DISPLAY 0.659574 (260 -690);
PAINT MONO (260 -690);
DISPLAY INVISIBLE (260 -690);
FORCEPROP 2 LAST CDS_LIB logical_power
J 0
(250 -750);
PAINT MONO (250 -750);
DISPLAY INVISIBLE (250 -750);
FORCEPROP 1 LAST HDL_POWER GND
J 1
(275 -825);
DISPLAY 0.872340 (275 -825);
PAINT GREEN (275 -825);
DISPLAY INVISIBLE (275 -825);
FORCEPROP 1 LAST PATH I4
J 0
(325 -750);
DISPLAY 0.872340 (325 -750);
PAINT AQUA (325 -750);
DISPLAY INVISIBLE (325 -750);
FORCEADD SOCKET4677_AZIF0045P001C01CS..38
(1700 1775);
FORCEPROP 1 LAST PART_NUMBER DGA^7000023
J 0
(650 4025);
DISPLAY 0.723404 (650 4025);
PAINT GREEN (650 4025);
DISPLAY INVISIBLE (650 4025);
FORCEPROP 1 LAST MATERIAL IO
J 0
(650 3950);
DISPLAY 0.723404 (650 3950);
PAINT GREEN (650 3950);
FORCEPROP 2 LAST VALUE SOCKET4677_AZIF0045-P001C01CS
J 0
(650 4150);
DISPLAY 1.021277 (650 4150);
FORCEPROP 2 LAST PART_TYPE SMLF
J 0
(650 4200);
DISPLAY 1.021277 (650 4200);
FORCEPROP 1 LAST $LOCATION U1
J 0
(650 4100);
DISPLAY 0.723404 (650 4100);
PAINT GREEN (650 4100);
FORCEPROP 0 LASTPIN (2900 -100) $PN AK12
J 0
(2910 -90);
DISPLAY 0.680851 (2910 -90);
PAINT MONO (2910 -90);
FORCEPROP 0 LASTPIN (2900 -50) $PN AK16
J 0
(2910 -40);
DISPLAY 0.680851 (2910 -40);
PAINT MONO (2910 -40);
FORCEPROP 0 LASTPIN (2900 0) $PN AK18
J 0
(2910 10);
DISPLAY 0.680851 (2910 10);
PAINT MONO (2910 10);
FORCEPROP 0 LASTPIN (2900 50) $PN AK24
J 0
(2910 60);
DISPLAY 0.680851 (2910 60);
PAINT MONO (2910 60);
FORCEPROP 0 LASTPIN (2900 100) $PN AK30
J 0
(2910 110);
DISPLAY 0.680851 (2910 110);
PAINT MONO (2910 110);
FORCEPROP 0 LASTPIN (2900 150) $PN AK36
J 0
(2910 160);
DISPLAY 0.680851 (2910 160);
PAINT MONO (2910 160);
FORCEPROP 0 LASTPIN (2900 -200) $PN AK4
J 0
(2910 -190);
DISPLAY 0.680851 (2910 -190);
PAINT MONO (2910 -190);
FORCEPROP 0 LASTPIN (2900 200) $PN AK42
J 0
(2910 210);
DISPLAY 0.680851 (2910 210);
PAINT MONO (2910 210);
FORCEPROP 0 LASTPIN (2900 250) $PN AK49
J 0
(2910 260);
DISPLAY 0.680851 (2910 260);
PAINT MONO (2910 260);
FORCEPROP 0 LASTPIN (2900 300) $PN AK55
J 0
(2910 310);
DISPLAY 0.680851 (2910 310);
PAINT MONO (2910 310);
FORCEPROP 0 LASTPIN (2900 350) $PN AK61
J 0
(2910 360);
DISPLAY 0.680851 (2910 360);
PAINT MONO (2910 360);
FORCEPROP 0 LASTPIN (2900 400) $PN AK67
J 0
(2910 410);
DISPLAY 0.680851 (2910 410);
PAINT MONO (2910 410);
FORCEPROP 0 LASTPIN (2900 450) $PN AK73
J 0
(2910 460);
DISPLAY 0.680851 (2910 460);
PAINT MONO (2910 460);
FORCEPROP 0 LASTPIN (2900 500) $PN AK79
J 0
(2910 510);
DISPLAY 0.680851 (2910 510);
PAINT MONO (2910 510);
FORCEPROP 0 LASTPIN (2900 -150) $PN AK8
J 0
(2910 -140);
DISPLAY 0.680851 (2910 -140);
PAINT MONO (2910 -140);
FORCEPROP 0 LASTPIN (2900 550) $PN AK81
J 0
(2910 560);
DISPLAY 0.680851 (2910 560);
PAINT MONO (2910 560);
FORCEPROP 0 LASTPIN (2900 600) $PN AK83
J 0
(2910 610);
DISPLAY 0.680851 (2910 610);
PAINT MONO (2910 610);
FORCEPROP 0 LASTPIN (2900 650) $PN AK87
J 0
(2910 660);
DISPLAY 0.680851 (2910 660);
PAINT MONO (2910 660);
FORCEPROP 0 LASTPIN (2900 700) $PN AK91
J 0
(2910 710);
DISPLAY 0.680851 (2910 710);
PAINT MONO (2910 710);
FORCEPROP 0 LASTPIN (2900 750) $PN AL1
J 0
(2910 760);
DISPLAY 0.680851 (2910 760);
PAINT MONO (2910 760);
FORCEPROP 0 LASTPIN (2900 900) $PN AL13
J 0
(2910 910);
DISPLAY 0.680851 (2910 910);
PAINT MONO (2910 910);
FORCEPROP 0 LASTPIN (2900 950) $PN AL17
J 0
(2910 960);
DISPLAY 0.680851 (2910 960);
PAINT MONO (2910 960);
FORCEPROP 0 LASTPIN (2900 800) $PN AL5
J 0
(2910 810);
DISPLAY 0.680851 (2910 810);
PAINT MONO (2910 810);
FORCEPROP 0 LASTPIN (2900 1000) $PN AL52
J 0
(2910 1010);
DISPLAY 0.680851 (2910 1010);
PAINT MONO (2910 1010);
FORCEPROP 0 LASTPIN (2900 1050) $PN AL80
J 0
(2910 1060);
DISPLAY 0.680851 (2910 1060);
PAINT MONO (2910 1060);
FORCEPROP 0 LASTPIN (2900 1100) $PN AL82
J 0
(2910 1110);
DISPLAY 0.680851 (2910 1110);
PAINT MONO (2910 1110);
FORCEPROP 0 LASTPIN (2900 1150) $PN AL84
J 0
(2910 1160);
DISPLAY 0.680851 (2910 1160);
PAINT MONO (2910 1160);
FORCEPROP 0 LASTPIN (2900 1200) $PN AL88
J 0
(2910 1210);
DISPLAY 0.680851 (2910 1210);
PAINT MONO (2910 1210);
FORCEPROP 0 LASTPIN (2900 850) $PN AL9
J 0
(2910 860);
DISPLAY 0.680851 (2910 860);
PAINT MONO (2910 860);
FORCEPROP 0 LASTPIN (2900 1350) $PN AM12
J 0
(2910 1360);
DISPLAY 0.680851 (2910 1360);
PAINT MONO (2910 1360);
FORCEPROP 0 LASTPIN (2900 1400) $PN AM16
J 0
(2910 1410);
DISPLAY 0.680851 (2910 1410);
PAINT MONO (2910 1410);
FORCEPROP 0 LASTPIN (2900 1450) $PN AM18
J 0
(2910 1460);
DISPLAY 0.680851 (2910 1460);
PAINT MONO (2910 1460);
FORCEPROP 0 LASTPIN (2900 1500) $PN AM20
J 0
(2910 1510);
DISPLAY 0.680851 (2910 1510);
PAINT MONO (2910 1510);
FORCEPROP 0 LASTPIN (2900 1550) $PN AM22
J 0
(2910 1560);
DISPLAY 0.680851 (2910 1560);
PAINT MONO (2910 1560);
FORCEPROP 0 LASTPIN (2900 1600) $PN AM24
J 0
(2910 1610);
DISPLAY 0.680851 (2910 1610);
PAINT MONO (2910 1610);
FORCEPROP 0 LASTPIN (2900 1650) $PN AM26
J 0
(2910 1660);
DISPLAY 0.680851 (2910 1660);
PAINT MONO (2910 1660);
FORCEPROP 0 LASTPIN (2900 1700) $PN AM28
J 0
(2910 1710);
DISPLAY 0.680851 (2910 1710);
PAINT MONO (2910 1710);
FORCEPROP 0 LASTPIN (2900 1750) $PN AM30
J 0
(2910 1760);
DISPLAY 0.680851 (2910 1760);
PAINT MONO (2910 1760);
FORCEPROP 0 LASTPIN (2900 1800) $PN AM32
J 0
(2910 1810);
DISPLAY 0.680851 (2910 1810);
PAINT MONO (2910 1810);
FORCEPROP 0 LASTPIN (2900 1850) $PN AM34
J 0
(2910 1860);
DISPLAY 0.680851 (2910 1860);
PAINT MONO (2910 1860);
FORCEPROP 0 LASTPIN (2900 1900) $PN AM36
J 0
(2910 1910);
DISPLAY 0.680851 (2910 1910);
PAINT MONO (2910 1910);
FORCEPROP 0 LASTPIN (2900 1950) $PN AM38
J 0
(2910 1960);
DISPLAY 0.680851 (2910 1960);
PAINT MONO (2910 1960);
FORCEPROP 0 LASTPIN (2900 1250) $PN AM4
J 0
(2910 1260);
DISPLAY 0.680851 (2910 1260);
PAINT MONO (2910 1260);
FORCEPROP 0 LASTPIN (2900 2000) $PN AM40
J 0
(2910 2010);
DISPLAY 0.680851 (2910 2010);
PAINT MONO (2910 2010);
FORCEPROP 0 LASTPIN (2900 2050) $PN AM42
J 0
(2910 2060);
DISPLAY 0.680851 (2910 2060);
PAINT MONO (2910 2060);
FORCEPROP 0 LASTPIN (2900 2100) $PN AM44
J 0
(2910 2110);
DISPLAY 0.680851 (2910 2110);
PAINT MONO (2910 2110);
FORCEPROP 0 LASTPIN (2900 2150) $PN AM47
J 0
(2910 2160);
DISPLAY 0.680851 (2910 2160);
PAINT MONO (2910 2160);
FORCEPROP 0 LASTPIN (2900 2200) $PN AM49
J 0
(2910 2210);
DISPLAY 0.680851 (2910 2210);
PAINT MONO (2910 2210);
FORCEPROP 0 LASTPIN (2900 2250) $PN AM51
J 0
(2910 2260);
DISPLAY 0.680851 (2910 2260);
PAINT MONO (2910 2260);
FORCEPROP 0 LASTPIN (2900 2300) $PN AM53
J 0
(2910 2310);
DISPLAY 0.680851 (2910 2310);
PAINT MONO (2910 2310);
FORCEPROP 0 LASTPIN (2900 2350) $PN AM55
J 0
(2910 2360);
DISPLAY 0.680851 (2910 2360);
PAINT MONO (2910 2360);
FORCEPROP 0 LASTPIN (2900 2400) $PN AM57
J 0
(2910 2410);
DISPLAY 0.680851 (2910 2410);
PAINT MONO (2910 2410);
FORCEPROP 0 LASTPIN (2900 2450) $PN AM59
J 0
(2910 2460);
DISPLAY 0.680851 (2910 2460);
PAINT MONO (2910 2460);
FORCEPROP 0 LASTPIN (2900 2500) $PN AM61
J 0
(2910 2510);
DISPLAY 0.680851 (2910 2510);
PAINT MONO (2910 2510);
FORCEPROP 0 LASTPIN (2900 2550) $PN AM63
J 0
(2910 2560);
DISPLAY 0.680851 (2910 2560);
PAINT MONO (2910 2560);
FORCEPROP 0 LASTPIN (2900 2600) $PN AM65
J 0
(2910 2610);
DISPLAY 0.680851 (2910 2610);
PAINT MONO (2910 2610);
FORCEPROP 0 LASTPIN (2900 2650) $PN AM67
J 0
(2910 2660);
DISPLAY 0.680851 (2910 2660);
PAINT MONO (2910 2660);
FORCEPROP 0 LASTPIN (2900 2700) $PN AM69
J 0
(2910 2710);
DISPLAY 0.680851 (2910 2710);
PAINT MONO (2910 2710);
FORCEPROP 0 LASTPIN (2900 2750) $PN AM71
J 0
(2910 2760);
DISPLAY 0.680851 (2910 2760);
PAINT MONO (2910 2760);
FORCEPROP 0 LASTPIN (2900 2800) $PN AM73
J 0
(2910 2810);
DISPLAY 0.680851 (2910 2810);
PAINT MONO (2910 2810);
FORCEPROP 0 LASTPIN (2900 2850) $PN AM75
J 0
(2910 2860);
DISPLAY 0.680851 (2910 2860);
PAINT MONO (2910 2860);
FORCEPROP 0 LASTPIN (2900 2900) $PN AM77
J 0
(2910 2910);
DISPLAY 0.680851 (2910 2910);
PAINT MONO (2910 2910);
FORCEPROP 0 LASTPIN (2900 1300) $PN AM8
J 0
(2910 1310);
DISPLAY 0.680851 (2910 1310);
PAINT MONO (2910 1310);
FORCEPROP 0 LASTPIN (2900 2950) $PN AN52
J 0
(2910 2960);
DISPLAY 0.680851 (2910 2960);
PAINT MONO (2910 2960);
FORCEPROP 0 LASTPIN (2900 3000) $PN AN84
J 0
(2910 3010);
DISPLAY 0.680851 (2910 3010);
PAINT MONO (2910 3010);
FORCEPROP 0 LASTPIN (2900 3050) $PN AN88
J 0
(2910 3060);
DISPLAY 0.680851 (2910 3060);
PAINT MONO (2910 3060);
FORCEPROP 0 LASTPIN (2900 3200) $PN AP12
J 0
(2910 3210);
DISPLAY 0.680851 (2910 3210);
PAINT MONO (2910 3210);
FORCEPROP 0 LASTPIN (2900 3250) $PN AP16
J 0
(2910 3260);
DISPLAY 0.680851 (2910 3260);
PAINT MONO (2910 3260);
FORCEPROP 0 LASTPIN (2900 3300) $PN AP18
J 0
(2910 3310);
DISPLAY 0.680851 (2910 3310);
PAINT MONO (2910 3310);
FORCEPROP 0 LASTPIN (2900 3350) $PN AP24
J 0
(2910 3360);
DISPLAY 0.680851 (2910 3360);
PAINT MONO (2910 3360);
FORCEPROP 0 LASTPIN (2900 3400) $PN AP30
J 0
(2910 3410);
DISPLAY 0.680851 (2910 3410);
PAINT MONO (2910 3410);
FORCEPROP 0 LASTPIN (2900 3450) $PN AP36
J 0
(2910 3460);
DISPLAY 0.680851 (2910 3460);
PAINT MONO (2910 3460);
FORCEPROP 0 LASTPIN (2900 3100) $PN AP4
J 0
(2910 3110);
DISPLAY 0.680851 (2910 3110);
PAINT MONO (2910 3110);
FORCEPROP 0 LASTPIN (2900 3500) $PN AP42
J 0
(2910 3510);
DISPLAY 0.680851 (2910 3510);
PAINT MONO (2910 3510);
FORCEPROP 0 LASTPIN (2900 3550) $PN AP49
J 0
(2910 3560);
DISPLAY 0.680851 (2910 3560);
PAINT MONO (2910 3560);
FORCEPROP 0 LASTPIN (2900 3600) $PN AP55
J 0
(2910 3610);
DISPLAY 0.680851 (2910 3610);
PAINT MONO (2910 3610);
FORCEPROP 0 LASTPIN (2900 3650) $PN AP61
J 0
(2910 3660);
DISPLAY 0.680851 (2910 3660);
PAINT MONO (2910 3660);
FORCEPROP 0 LASTPIN (2900 3700) $PN AP67
J 0
(2910 3710);
DISPLAY 0.680851 (2910 3710);
PAINT MONO (2910 3710);
FORCEPROP 0 LASTPIN (2900 3750) $PN AP73
J 0
(2910 3760);
DISPLAY 0.680851 (2910 3760);
PAINT MONO (2910 3760);
FORCEPROP 0 LASTPIN (500 -200) $PN AP79
J 2
(490 -190);
DISPLAY 0.680851 (490 -190);
PAINT MONO (490 -190);
FORCEPROP 0 LASTPIN (2900 3150) $PN AP8
J 0
(2910 3160);
DISPLAY 0.680851 (2910 3160);
PAINT MONO (2910 3160);
FORCEPROP 0 LASTPIN (500 -150) $PN AP83
J 2
(490 -140);
DISPLAY 0.680851 (490 -140);
PAINT MONO (490 -140);
FORCEPROP 0 LASTPIN (500 -100) $PN AP87
J 2
(490 -90);
DISPLAY 0.680851 (490 -90);
PAINT MONO (490 -90);
FORCEPROP 0 LASTPIN (500 -50) $PN AP91
J 2
(490 -40);
DISPLAY 0.680851 (490 -40);
PAINT MONO (490 -40);
FORCEPROP 0 LASTPIN (500 0) $PN AR1
J 2
(490 10);
DISPLAY 0.680851 (490 10);
PAINT MONO (490 10);
FORCEPROP 0 LASTPIN (500 150) $PN AR13
J 2
(490 160);
DISPLAY 0.680851 (490 160);
PAINT MONO (490 160);
FORCEPROP 0 LASTPIN (500 200) $PN AR19
J 2
(490 210);
DISPLAY 0.680851 (490 210);
PAINT MONO (490 210);
FORCEPROP 0 LASTPIN (500 250) $PN AR23
J 2
(490 260);
DISPLAY 0.680851 (490 260);
PAINT MONO (490 260);
FORCEPROP 0 LASTPIN (500 300) $PN AR25
J 2
(490 310);
DISPLAY 0.680851 (490 310);
PAINT MONO (490 310);
FORCEPROP 0 LASTPIN (500 350) $PN AR29
J 2
(490 360);
DISPLAY 0.680851 (490 360);
PAINT MONO (490 360);
FORCEPROP 0 LASTPIN (500 400) $PN AR31
J 2
(490 410);
DISPLAY 0.680851 (490 410);
PAINT MONO (490 410);
FORCEPROP 0 LASTPIN (500 450) $PN AR35
J 2
(490 460);
DISPLAY 0.680851 (490 460);
PAINT MONO (490 460);
FORCEPROP 0 LASTPIN (500 500) $PN AR37
J 2
(490 510);
DISPLAY 0.680851 (490 510);
PAINT MONO (490 510);
FORCEPROP 0 LASTPIN (500 550) $PN AR41
J 2
(490 560);
DISPLAY 0.680851 (490 560);
PAINT MONO (490 560);
FORCEPROP 0 LASTPIN (500 600) $PN AR43
J 2
(490 610);
DISPLAY 0.680851 (490 610);
PAINT MONO (490 610);
FORCEPROP 0 LASTPIN (500 650) $PN AR48
J 2
(490 660);
DISPLAY 0.680851 (490 660);
PAINT MONO (490 660);
FORCEPROP 0 LASTPIN (500 50) $PN AR5
J 2
(490 60);
DISPLAY 0.680851 (490 60);
PAINT MONO (490 60);
FORCEPROP 0 LASTPIN (500 700) $PN AR50
J 2
(490 710);
DISPLAY 0.680851 (490 710);
PAINT MONO (490 710);
FORCEPROP 0 LASTPIN (500 750) $PN AR54
J 2
(490 760);
DISPLAY 0.680851 (490 760);
PAINT MONO (490 760);
FORCEPROP 0 LASTPIN (500 800) $PN AR56
J 2
(490 810);
DISPLAY 0.680851 (490 810);
PAINT MONO (490 810);
FORCEPROP 0 LASTPIN (500 850) $PN AR60
J 2
(490 860);
DISPLAY 0.680851 (490 860);
PAINT MONO (490 860);
FORCEPROP 0 LASTPIN (500 900) $PN AR62
J 2
(490 910);
DISPLAY 0.680851 (490 910);
PAINT MONO (490 910);
FORCEPROP 0 LASTPIN (500 950) $PN AR66
J 2
(490 960);
DISPLAY 0.680851 (490 960);
PAINT MONO (490 960);
FORCEPROP 0 LASTPIN (500 1000) $PN AR68
J 2
(490 1010);
DISPLAY 0.680851 (490 1010);
PAINT MONO (490 1010);
FORCEPROP 0 LASTPIN (500 1050) $PN AR72
J 2
(490 1060);
DISPLAY 0.680851 (490 1060);
PAINT MONO (490 1060);
FORCEPROP 0 LASTPIN (500 1100) $PN AR74
J 2
(490 1110);
DISPLAY 0.680851 (490 1110);
PAINT MONO (490 1110);
FORCEPROP 0 LASTPIN (500 1150) $PN AR78
J 2
(490 1160);
DISPLAY 0.680851 (490 1160);
PAINT MONO (490 1160);
FORCEPROP 0 LASTPIN (500 1200) $PN AR82
J 2
(490 1210);
DISPLAY 0.680851 (490 1210);
PAINT MONO (490 1210);
FORCEPROP 0 LASTPIN (500 1250) $PN AR84
J 2
(490 1260);
DISPLAY 0.680851 (490 1260);
PAINT MONO (490 1260);
FORCEPROP 0 LASTPIN (500 1300) $PN AR88
J 2
(490 1310);
DISPLAY 0.680851 (490 1310);
PAINT MONO (490 1310);
FORCEPROP 0 LASTPIN (500 100) $PN AR9
J 2
(490 110);
DISPLAY 0.680851 (490 110);
PAINT MONO (490 110);
FORCEPROP 0 LASTPIN (500 1450) $PN AT12
J 2
(490 1460);
DISPLAY 0.680851 (490 1460);
PAINT MONO (490 1460);
FORCEPROP 0 LASTPIN (500 1500) $PN AT16
J 2
(490 1510);
DISPLAY 0.680851 (490 1510);
PAINT MONO (490 1510);
FORCEPROP 0 LASTPIN (500 1550) $PN AT20
J 2
(490 1560);
DISPLAY 0.680851 (490 1560);
PAINT MONO (490 1560);
FORCEPROP 0 LASTPIN (500 1600) $PN AT22
J 2
(490 1610);
DISPLAY 0.680851 (490 1610);
PAINT MONO (490 1610);
FORCEPROP 0 LASTPIN (500 1650) $PN AT26
J 2
(490 1660);
DISPLAY 0.680851 (490 1660);
PAINT MONO (490 1660);
FORCEPROP 0 LASTPIN (500 1700) $PN AT28
J 2
(490 1710);
DISPLAY 0.680851 (490 1710);
PAINT MONO (490 1710);
FORCEPROP 0 LASTPIN (500 1750) $PN AT32
J 2
(490 1760);
DISPLAY 0.680851 (490 1760);
PAINT MONO (490 1760);
FORCEPROP 0 LASTPIN (500 1800) $PN AT34
J 2
(490 1810);
DISPLAY 0.680851 (490 1810);
PAINT MONO (490 1810);
FORCEPROP 0 LASTPIN (500 1850) $PN AT38
J 2
(490 1860);
DISPLAY 0.680851 (490 1860);
PAINT MONO (490 1860);
FORCEPROP 0 LASTPIN (500 1350) $PN AT4
J 2
(490 1360);
DISPLAY 0.680851 (490 1360);
PAINT MONO (490 1360);
FORCEPROP 0 LASTPIN (500 1900) $PN AT40
J 2
(490 1910);
DISPLAY 0.680851 (490 1910);
PAINT MONO (490 1910);
FORCEPROP 0 LASTPIN (500 1950) $PN AT44
J 2
(490 1960);
DISPLAY 0.680851 (490 1960);
PAINT MONO (490 1960);
FORCEPROP 0 LASTPIN (500 2000) $PN AT51
J 2
(490 2010);
DISPLAY 0.680851 (490 2010);
PAINT MONO (490 2010);
FORCEPROP 0 LASTPIN (500 2050) $PN AT53
J 2
(490 2060);
DISPLAY 0.680851 (490 2060);
PAINT MONO (490 2060);
FORCEPROP 0 LASTPIN (500 2100) $PN AT57
J 2
(490 2110);
DISPLAY 0.680851 (490 2110);
PAINT MONO (490 2110);
FORCEPROP 0 LASTPIN (500 2150) $PN AT59
J 2
(490 2160);
DISPLAY 0.680851 (490 2160);
PAINT MONO (490 2160);
FORCEPROP 0 LASTPIN (500 2200) $PN AT63
J 2
(490 2210);
DISPLAY 0.680851 (490 2210);
PAINT MONO (490 2210);
FORCEPROP 0 LASTPIN (500 2250) $PN AT65
J 2
(490 2260);
DISPLAY 0.680851 (490 2260);
PAINT MONO (490 2260);
FORCEPROP 0 LASTPIN (500 2300) $PN AT69
J 2
(490 2310);
DISPLAY 0.680851 (490 2310);
PAINT MONO (490 2310);
FORCEPROP 0 LASTPIN (500 2350) $PN AT71
J 2
(490 2360);
DISPLAY 0.680851 (490 2360);
PAINT MONO (490 2360);
FORCEPROP 0 LASTPIN (500 2400) $PN AT75
J 2
(490 2410);
DISPLAY 0.680851 (490 2410);
PAINT MONO (490 2410);
FORCEPROP 0 LASTPIN (500 2450) $PN AT77
J 2
(490 2460);
DISPLAY 0.680851 (490 2460);
PAINT MONO (490 2460);
FORCEPROP 0 LASTPIN (500 2500) $PN AT79
J 2
(490 2510);
DISPLAY 0.680851 (490 2510);
PAINT MONO (490 2510);
FORCEPROP 0 LASTPIN (500 1400) $PN AT8
J 2
(490 1410);
DISPLAY 0.680851 (490 1410);
PAINT MONO (490 1410);
FORCEPROP 0 LASTPIN (500 2550) $PN AU27
J 2
(490 2560);
DISPLAY 0.680851 (490 2560);
PAINT MONO (490 2560);
FORCEPROP 0 LASTPIN (500 2600) $PN AU31
J 2
(490 2610);
DISPLAY 0.680851 (490 2610);
PAINT MONO (490 2610);
FORCEPROP 0 LASTPIN (500 2650) $PN AU37
J 2
(490 2660);
DISPLAY 0.680851 (490 2660);
PAINT MONO (490 2660);
FORCEPROP 0 LASTPIN (500 2700) $PN AU39
J 2
(490 2710);
DISPLAY 0.680851 (490 2710);
PAINT MONO (490 2710);
FORCEPROP 0 LASTPIN (500 2750) $PN AU41
J 2
(490 2760);
DISPLAY 0.680851 (490 2760);
PAINT MONO (490 2760);
FORCEPROP 0 LASTPIN (500 2800) $PN AU45
J 2
(490 2810);
DISPLAY 0.680851 (490 2810);
PAINT MONO (490 2810);
FORCEPROP 0 LASTPIN (500 2850) $PN AU48
J 2
(490 2860);
DISPLAY 0.680851 (490 2860);
PAINT MONO (490 2860);
FORCEPROP 0 LASTPIN (500 2900) $PN AU70
J 2
(490 2910);
DISPLAY 0.680851 (490 2910);
PAINT MONO (490 2910);
FORCEPROP 0 LASTPIN (500 2950) $PN AU72
J 2
(490 2960);
DISPLAY 0.680851 (490 2960);
PAINT MONO (490 2960);
FORCEPROP 0 LASTPIN (500 3000) $PN AU74
J 2
(490 3010);
DISPLAY 0.680851 (490 3010);
PAINT MONO (490 3010);
FORCEPROP 0 LASTPIN (500 3050) $PN AU76
J 2
(490 3060);
DISPLAY 0.680851 (490 3060);
PAINT MONO (490 3060);
FORCEPROP 0 LASTPIN (500 3100) $PN AU80
J 2
(490 3110);
DISPLAY 0.680851 (490 3110);
PAINT MONO (490 3110);
FORCEPROP 0 LASTPIN (500 3150) $PN AU84
J 2
(490 3160);
DISPLAY 0.680851 (490 3160);
PAINT MONO (490 3160);
FORCEPROP 0 LASTPIN (500 3200) $PN AU88
J 2
(490 3210);
DISPLAY 0.680851 (490 3210);
PAINT MONO (490 3210);
FORCEPROP 0 LASTPIN (500 3350) $PN AV12
J 2
(490 3360);
DISPLAY 0.680851 (490 3360);
PAINT MONO (490 3360);
FORCEPROP 0 LASTPIN (500 3400) $PN AV16
J 2
(490 3410);
DISPLAY 0.680851 (490 3410);
PAINT MONO (490 3410);
FORCEPROP 0 LASTPIN (500 3250) $PN AV4
J 2
(490 3260);
DISPLAY 0.680851 (490 3260);
PAINT MONO (490 3260);
FORCEPROP 0 LASTPIN (500 3450) $PN AV77
J 2
(490 3460);
DISPLAY 0.680851 (490 3460);
PAINT MONO (490 3460);
FORCEPROP 0 LASTPIN (500 3300) $PN AV8
J 2
(490 3310);
DISPLAY 0.680851 (490 3310);
PAINT MONO (490 3310);
FORCEPROP 0 LASTPIN (500 3500) $PN AV87
J 2
(490 3510);
DISPLAY 0.680851 (490 3510);
PAINT MONO (490 3510);
FORCEPROP 0 LASTPIN (500 3550) $PN AV91
J 2
(490 3560);
DISPLAY 0.680851 (490 3560);
PAINT MONO (490 3560);
FORCEPROP 0 LASTPIN (500 3600) $PN AW1
J 2
(490 3610);
DISPLAY 0.680851 (490 3610);
PAINT MONO (490 3610);
FORCEPROP 0 LASTPIN (500 3750) $PN AW13
J 2
(490 3760);
DISPLAY 0.680851 (490 3760);
PAINT MONO (490 3760);
FORCEPROP 0 LASTPIN (500 3650) $PN AW5
J 2
(490 3660);
DISPLAY 0.680851 (490 3660);
PAINT MONO (490 3660);
FORCEPROP 0 LASTPIN (500 3700) $PN AW9
J 2
(490 3710);
DISPLAY 0.680851 (490 3710);
PAINT MONO (490 3710);
FORCEPROP 2 LAST CDS_LIB pure_quanta
J 0
(1700 1775);
DISPLAY INVISIBLE (1700 1775);
FORCEPROP 1 LAST NEEDS_NO_SIZE TRUE
J 0
(1700 1775);
DISPLAY 0.723404 (1700 1775);
PAINT GREEN (1700 1775);
DISPLAY INVISIBLE (1700 1775);
FORCEPROP 1 LAST CDS_LMAN_SYM_OUTLINE -1050,2150,1050,-2100
J 0
(1700 1775);
DISPLAY 0.468085 (1700 1775);
PAINT GREEN (1700 1775);
DISPLAY INVISIBLE (1700 1775);
FORCEPROP 0 LAST CDS_LOCATION U1
J 0
(650 4250);
DISPLAY 1.021277 (650 4250);
DISPLAY INVISIBLE (650 4250);
FORCEPROP 0 LAST $SEC 38
J 0
(650 4250);
DISPLAY 0.680851 (650 4250);
PAINT MONO (650 4250);
DISPLAY INVISIBLE (650 4250);
FORCEPROP 2 LAST CDS_SEC 38
J 0
(650 4250);
DISPLAY 1.021277 (650 4250);
DISPLAY INVISIBLE (650 4250);
FORCEPROP 1 LAST PATH I5
J 0
(1700 1775);
DISPLAY 0.723404 (1700 1775);
PAINT GREEN (1700 1775);
DISPLAY INVISIBLE (1700 1775);
FORCEADD UNIVERSAL_GND..1
(3150 -750);
FORCEPROP 3 LASTPIN (3150 -700) SIG_NAME GND\g
J 0
(3160 -690);
DISPLAY 0.659574 (3160 -690);
PAINT MONO (3160 -690);
DISPLAY INVISIBLE (3160 -690);
FORCEPROP 2 LAST CDS_LIB logical_power
J 0
(3150 -750);
PAINT MONO (3150 -750);
DISPLAY INVISIBLE (3150 -750);
FORCEPROP 1 LAST HDL_POWER GND
J 1
(3175 -825);
DISPLAY 0.872340 (3175 -825);
PAINT GREEN (3175 -825);
DISPLAY INVISIBLE (3175 -825);
FORCEPROP 1 LAST PATH I6
J 0
(3225 -750);
DISPLAY 0.872340 (3225 -750);
PAINT AQUA (3225 -750);
DISPLAY INVISIBLE (3225 -750);
FORCEADD UNIVERSAL_GND..1
(3275 -750);
FORCEPROP 3 LASTPIN (3275 -700) SIG_NAME GND\g
J 0
(3285 -690);
DISPLAY 0.659574 (3285 -690);
PAINT MONO (3285 -690);
DISPLAY INVISIBLE (3285 -690);
FORCEPROP 2 LAST CDS_LIB logical_power
J 0
(3275 -750);
PAINT MONO (3275 -750);
DISPLAY INVISIBLE (3275 -750);
FORCEPROP 1 LAST HDL_POWER GND
J 1
(3300 -825);
DISPLAY 0.872340 (3300 -825);
PAINT GREEN (3300 -825);
DISPLAY INVISIBLE (3300 -825);
FORCEPROP 1 LAST PATH I7
J 0
(3350 -750);
DISPLAY 0.872340 (3350 -750);
PAINT AQUA (3350 -750);
DISPLAY INVISIBLE (3350 -750);
FORCEADD SOCKET4677_AZIF0045P001C01CS..39
(4725 1775);
FORCEPROP 1 LAST PART_NUMBER DGA^7000023
J 0
(3675 4025);
DISPLAY 0.723404 (3675 4025);
PAINT GREEN (3675 4025);
DISPLAY INVISIBLE (3675 4025);
FORCEPROP 2 LAST PART_TYPE SMLF
J 0
(3675 4200);
DISPLAY 1.021277 (3675 4200);
FORCEPROP 1 LAST MATERIAL IO
J 0
(3675 3950);
DISPLAY 0.723404 (3675 3950);
PAINT GREEN (3675 3950);
FORCEPROP 2 LAST VALUE SOCKET4677_AZIF0045-P001C01CS
J 0
(3675 4150);
DISPLAY 1.021277 (3675 4150);
FORCEPROP 1 LAST $LOCATION U1
J 0
(3675 4100);
DISPLAY 0.723404 (3675 4100);
PAINT GREEN (3675 4100);
FORCEPROP 0 LASTPIN (5925 -200) $PN AA82
J 0
(5935 -190);
DISPLAY 0.680851 (5935 -190);
PAINT MONO (5935 -190);
FORCEPROP 0 LASTPIN (5925 -150) $PN AA84
J 0
(5935 -140);
DISPLAY 0.680851 (5935 -140);
PAINT MONO (5935 -140);
FORCEPROP 0 LASTPIN (5925 -100) $PN AA88
J 0
(5935 -90);
DISPLAY 0.680851 (5935 -90);
PAINT MONO (5935 -90);
FORCEPROP 0 LASTPIN (5925 50) $PN AB12
J 0
(5935 60);
DISPLAY 0.680851 (5935 60);
PAINT MONO (5935 60);
FORCEPROP 0 LASTPIN (5925 100) $PN AB16
J 0
(5935 110);
DISPLAY 0.680851 (5935 110);
PAINT MONO (5935 110);
FORCEPROP 0 LASTPIN (5925 150) $PN AB20
J 0
(5935 160);
DISPLAY 0.680851 (5935 160);
PAINT MONO (5935 160);
FORCEPROP 0 LASTPIN (5925 200) $PN AB22
J 0
(5935 210);
DISPLAY 0.680851 (5935 210);
PAINT MONO (5935 210);
FORCEPROP 0 LASTPIN (5925 250) $PN AB26
J 0
(5935 260);
DISPLAY 0.680851 (5935 260);
PAINT MONO (5935 260);
FORCEPROP 0 LASTPIN (5925 300) $PN AB28
J 0
(5935 310);
DISPLAY 0.680851 (5935 310);
PAINT MONO (5935 310);
FORCEPROP 0 LASTPIN (5925 350) $PN AB32
J 0
(5935 360);
DISPLAY 0.680851 (5935 360);
PAINT MONO (5935 360);
FORCEPROP 0 LASTPIN (5925 400) $PN AB34
J 0
(5935 410);
DISPLAY 0.680851 (5935 410);
PAINT MONO (5935 410);
FORCEPROP 0 LASTPIN (5925 450) $PN AB38
J 0
(5935 460);
DISPLAY 0.680851 (5935 460);
PAINT MONO (5935 460);
FORCEPROP 0 LASTPIN (5925 -50) $PN AB4
J 0
(5935 -40);
DISPLAY 0.680851 (5935 -40);
PAINT MONO (5935 -40);
FORCEPROP 0 LASTPIN (5925 500) $PN AB40
J 0
(5935 510);
DISPLAY 0.680851 (5935 510);
PAINT MONO (5935 510);
FORCEPROP 0 LASTPIN (5925 550) $PN AB44
J 0
(5935 560);
DISPLAY 0.680851 (5935 560);
PAINT MONO (5935 560);
FORCEPROP 0 LASTPIN (5925 600) $PN AB47
J 0
(5935 610);
DISPLAY 0.680851 (5935 610);
PAINT MONO (5935 610);
FORCEPROP 0 LASTPIN (5925 650) $PN AB51
J 0
(5935 660);
DISPLAY 0.680851 (5935 660);
PAINT MONO (5935 660);
FORCEPROP 0 LASTPIN (5925 700) $PN AB53
J 0
(5935 710);
DISPLAY 0.680851 (5935 710);
PAINT MONO (5935 710);
FORCEPROP 0 LASTPIN (5925 750) $PN AB57
J 0
(5935 760);
DISPLAY 0.680851 (5935 760);
PAINT MONO (5935 760);
FORCEPROP 0 LASTPIN (5925 800) $PN AB59
J 0
(5935 810);
DISPLAY 0.680851 (5935 810);
PAINT MONO (5935 810);
FORCEPROP 0 LASTPIN (5925 850) $PN AB63
J 0
(5935 860);
DISPLAY 0.680851 (5935 860);
PAINT MONO (5935 860);
FORCEPROP 0 LASTPIN (5925 900) $PN AB65
J 0
(5935 910);
DISPLAY 0.680851 (5935 910);
PAINT MONO (5935 910);
FORCEPROP 0 LASTPIN (5925 950) $PN AB69
J 0
(5935 960);
DISPLAY 0.680851 (5935 960);
PAINT MONO (5935 960);
FORCEPROP 0 LASTPIN (5925 1000) $PN AB71
J 0
(5935 1010);
DISPLAY 0.680851 (5935 1010);
PAINT MONO (5935 1010);
FORCEPROP 0 LASTPIN (5925 1050) $PN AB75
J 0
(5935 1060);
DISPLAY 0.680851 (5935 1060);
PAINT MONO (5935 1060);
FORCEPROP 0 LASTPIN (5925 1100) $PN AB77
J 0
(5935 1110);
DISPLAY 0.680851 (5935 1110);
PAINT MONO (5935 1110);
FORCEPROP 0 LASTPIN (5925 1150) $PN AB79
J 0
(5935 1160);
DISPLAY 0.680851 (5935 1160);
PAINT MONO (5935 1160);
FORCEPROP 0 LASTPIN (5925 0) $PN AB8
J 0
(5935 10);
DISPLAY 0.680851 (5935 10);
PAINT MONO (5935 10);
FORCEPROP 0 LASTPIN (5925 1200) $PN AB81
J 0
(5935 1210);
DISPLAY 0.680851 (5935 1210);
PAINT MONO (5935 1210);
FORCEPROP 0 LASTPIN (5925 1250) $PN AB83
J 0
(5935 1260);
DISPLAY 0.680851 (5935 1260);
PAINT MONO (5935 1260);
FORCEPROP 0 LASTPIN (5925 1300) $PN AB87
J 0
(5935 1310);
DISPLAY 0.680851 (5935 1310);
PAINT MONO (5935 1310);
FORCEPROP 0 LASTPIN (5925 1350) $PN AB91
J 0
(5935 1360);
DISPLAY 0.680851 (5935 1360);
PAINT MONO (5935 1360);
FORCEPROP 0 LASTPIN (5925 1400) $PN AC1
J 0
(5935 1410);
DISPLAY 0.680851 (5935 1410);
PAINT MONO (5935 1410);
FORCEPROP 0 LASTPIN (5925 1550) $PN AC13
J 0
(5935 1560);
DISPLAY 0.680851 (5935 1560);
PAINT MONO (5935 1560);
FORCEPROP 0 LASTPIN (5925 1600) $PN AC21
J 0
(5935 1610);
DISPLAY 0.680851 (5935 1610);
PAINT MONO (5935 1610);
FORCEPROP 0 LASTPIN (5925 1650) $PN AC27
J 0
(5935 1660);
DISPLAY 0.680851 (5935 1660);
PAINT MONO (5935 1660);
FORCEPROP 0 LASTPIN (5925 1700) $PN AC33
J 0
(5935 1710);
DISPLAY 0.680851 (5935 1710);
PAINT MONO (5935 1710);
FORCEPROP 0 LASTPIN (5925 1750) $PN AC39
J 0
(5935 1760);
DISPLAY 0.680851 (5935 1760);
PAINT MONO (5935 1760);
FORCEPROP 0 LASTPIN (5925 1800) $PN AC45
J 0
(5935 1810);
DISPLAY 0.680851 (5935 1810);
PAINT MONO (5935 1810);
FORCEPROP 0 LASTPIN (5925 1450) $PN AC5
J 0
(5935 1460);
DISPLAY 0.680851 (5935 1460);
PAINT MONO (5935 1460);
FORCEPROP 0 LASTPIN (5925 1850) $PN AC52
J 0
(5935 1860);
DISPLAY 0.680851 (5935 1860);
PAINT MONO (5935 1860);
FORCEPROP 0 LASTPIN (5925 1900) $PN AC58
J 0
(5935 1910);
DISPLAY 0.680851 (5935 1910);
PAINT MONO (5935 1910);
FORCEPROP 0 LASTPIN (5925 1950) $PN AC64
J 0
(5935 1960);
DISPLAY 0.680851 (5935 1960);
PAINT MONO (5935 1960);
FORCEPROP 0 LASTPIN (5925 2000) $PN AC70
J 0
(5935 2010);
DISPLAY 0.680851 (5935 2010);
PAINT MONO (5935 2010);
FORCEPROP 0 LASTPIN (5925 2050) $PN AC76
J 0
(5935 2060);
DISPLAY 0.680851 (5935 2060);
PAINT MONO (5935 2060);
FORCEPROP 0 LASTPIN (5925 2100) $PN AC84
J 0
(5935 2110);
DISPLAY 0.680851 (5935 2110);
PAINT MONO (5935 2110);
FORCEPROP 0 LASTPIN (5925 2150) $PN AC88
J 0
(5935 2160);
DISPLAY 0.680851 (5935 2160);
PAINT MONO (5935 2160);
FORCEPROP 0 LASTPIN (5925 1500) $PN AC9
J 0
(5935 1510);
DISPLAY 0.680851 (5935 1510);
PAINT MONO (5935 1510);
FORCEPROP 0 LASTPIN (5925 2300) $PN AD12
J 0
(5935 2310);
DISPLAY 0.680851 (5935 2310);
PAINT MONO (5935 2310);
FORCEPROP 0 LASTPIN (5925 2350) $PN AD16
J 0
(5935 2360);
DISPLAY 0.680851 (5935 2360);
PAINT MONO (5935 2360);
FORCEPROP 0 LASTPIN (5925 2200) $PN AD4
J 0
(5935 2210);
DISPLAY 0.680851 (5935 2210);
PAINT MONO (5935 2210);
FORCEPROP 0 LASTPIN (5925 2400) $PN AD42
J 0
(5935 2410);
DISPLAY 0.680851 (5935 2410);
PAINT MONO (5935 2410);
FORCEPROP 0 LASTPIN (5925 2450) $PN AD79
J 0
(5935 2460);
DISPLAY 0.680851 (5935 2460);
PAINT MONO (5935 2460);
FORCEPROP 0 LASTPIN (5925 2250) $PN AD8
J 0
(5935 2260);
DISPLAY 0.680851 (5935 2260);
PAINT MONO (5935 2260);
FORCEPROP 0 LASTPIN (5925 2500) $PN AD83
J 0
(5935 2510);
DISPLAY 0.680851 (5935 2510);
PAINT MONO (5935 2510);
FORCEPROP 0 LASTPIN (5925 2550) $PN AE17
J 0
(5935 2560);
DISPLAY 0.680851 (5935 2560);
PAINT MONO (5935 2560);
FORCEPROP 0 LASTPIN (5925 2600) $PN AE19
J 0
(5935 2610);
DISPLAY 0.680851 (5935 2610);
PAINT MONO (5935 2610);
FORCEPROP 0 LASTPIN (5925 2650) $PN AE21
J 0
(5935 2660);
DISPLAY 0.680851 (5935 2660);
PAINT MONO (5935 2660);
FORCEPROP 0 LASTPIN (5925 2700) $PN AE23
J 0
(5935 2710);
DISPLAY 0.680851 (5935 2710);
PAINT MONO (5935 2710);
FORCEPROP 0 LASTPIN (5925 2750) $PN AE25
J 0
(5935 2760);
DISPLAY 0.680851 (5935 2760);
PAINT MONO (5935 2760);
FORCEPROP 0 LASTPIN (5925 2800) $PN AE27
J 0
(5935 2810);
DISPLAY 0.680851 (5935 2810);
PAINT MONO (5935 2810);
FORCEPROP 0 LASTPIN (5925 2850) $PN AE29
J 0
(5935 2860);
DISPLAY 0.680851 (5935 2860);
PAINT MONO (5935 2860);
FORCEPROP 0 LASTPIN (5925 2900) $PN AE31
J 0
(5935 2910);
DISPLAY 0.680851 (5935 2910);
PAINT MONO (5935 2910);
FORCEPROP 0 LASTPIN (5925 2950) $PN AE33
J 0
(5935 2960);
DISPLAY 0.680851 (5935 2960);
PAINT MONO (5935 2960);
FORCEPROP 0 LASTPIN (5925 3000) $PN AE35
J 0
(5935 3010);
DISPLAY 0.680851 (5935 3010);
PAINT MONO (5935 3010);
FORCEPROP 0 LASTPIN (5925 3050) $PN AE37
J 0
(5935 3060);
DISPLAY 0.680851 (5935 3060);
PAINT MONO (5935 3060);
FORCEPROP 0 LASTPIN (5925 3100) $PN AE39
J 0
(5935 3110);
DISPLAY 0.680851 (5935 3110);
PAINT MONO (5935 3110);
FORCEPROP 0 LASTPIN (5925 3150) $PN AE41
J 0
(5935 3160);
DISPLAY 0.680851 (5935 3160);
PAINT MONO (5935 3160);
FORCEPROP 0 LASTPIN (5925 3200) $PN AE43
J 0
(5935 3210);
DISPLAY 0.680851 (5935 3210);
PAINT MONO (5935 3210);
FORCEPROP 0 LASTPIN (5925 3250) $PN AE45
J 0
(5935 3260);
DISPLAY 0.680851 (5935 3260);
PAINT MONO (5935 3260);
FORCEPROP 0 LASTPIN (5925 3300) $PN AE48
J 0
(5935 3310);
DISPLAY 0.680851 (5935 3310);
PAINT MONO (5935 3310);
FORCEPROP 0 LASTPIN (5925 3350) $PN AE50
J 0
(5935 3360);
DISPLAY 0.680851 (5935 3360);
PAINT MONO (5935 3360);
FORCEPROP 0 LASTPIN (5925 3400) $PN AE52
J 0
(5935 3410);
DISPLAY 0.680851 (5935 3410);
PAINT MONO (5935 3410);
FORCEPROP 0 LASTPIN (5925 3450) $PN AE54
J 0
(5935 3460);
DISPLAY 0.680851 (5935 3460);
PAINT MONO (5935 3460);
FORCEPROP 0 LASTPIN (5925 3500) $PN AE56
J 0
(5935 3510);
DISPLAY 0.680851 (5935 3510);
PAINT MONO (5935 3510);
FORCEPROP 0 LASTPIN (5925 3550) $PN AE58
J 0
(5935 3560);
DISPLAY 0.680851 (5935 3560);
PAINT MONO (5935 3560);
FORCEPROP 0 LASTPIN (5925 3600) $PN AE60
J 0
(5935 3610);
DISPLAY 0.680851 (5935 3610);
PAINT MONO (5935 3610);
FORCEPROP 0 LASTPIN (5925 3650) $PN AE62
J 0
(5935 3660);
DISPLAY 0.680851 (5935 3660);
PAINT MONO (5935 3660);
FORCEPROP 0 LASTPIN (5925 3700) $PN AE64
J 0
(5935 3710);
DISPLAY 0.680851 (5935 3710);
PAINT MONO (5935 3710);
FORCEPROP 0 LASTPIN (5925 3750) $PN AE66
J 0
(5935 3760);
DISPLAY 0.680851 (5935 3760);
PAINT MONO (5935 3760);
FORCEPROP 0 LASTPIN (3525 -200) $PN AE68
J 2
(3515 -190);
DISPLAY 0.680851 (3515 -190);
PAINT MONO (3515 -190);
FORCEPROP 0 LASTPIN (3525 -150) $PN AE70
J 2
(3515 -140);
DISPLAY 0.680851 (3515 -140);
PAINT MONO (3515 -140);
FORCEPROP 0 LASTPIN (3525 -100) $PN AE72
J 2
(3515 -90);
DISPLAY 0.680851 (3515 -90);
PAINT MONO (3515 -90);
FORCEPROP 0 LASTPIN (3525 -50) $PN AE74
J 2
(3515 -40);
DISPLAY 0.680851 (3515 -40);
PAINT MONO (3515 -40);
FORCEPROP 0 LASTPIN (3525 0) $PN AE76
J 2
(3515 10);
DISPLAY 0.680851 (3515 10);
PAINT MONO (3515 10);
FORCEPROP 0 LASTPIN (3525 50) $PN AE78
J 2
(3515 60);
DISPLAY 0.680851 (3515 60);
PAINT MONO (3515 60);
FORCEPROP 0 LASTPIN (3525 100) $PN AE84
J 2
(3515 110);
DISPLAY 0.680851 (3515 110);
PAINT MONO (3515 110);
FORCEPROP 0 LASTPIN (3525 150) $PN AE88
J 2
(3515 160);
DISPLAY 0.680851 (3515 160);
PAINT MONO (3515 160);
FORCEPROP 0 LASTPIN (3525 300) $PN AF12
J 2
(3515 310);
DISPLAY 0.680851 (3515 310);
PAINT MONO (3515 310);
FORCEPROP 0 LASTPIN (3525 350) $PN AF16
J 2
(3515 360);
DISPLAY 0.680851 (3515 360);
PAINT MONO (3515 360);
FORCEPROP 0 LASTPIN (3525 200) $PN AF4
J 2
(3515 210);
DISPLAY 0.680851 (3515 210);
PAINT MONO (3515 210);
FORCEPROP 0 LASTPIN (3525 400) $PN AF42
J 2
(3515 410);
DISPLAY 0.680851 (3515 410);
PAINT MONO (3515 410);
FORCEPROP 0 LASTPIN (3525 250) $PN AF8
J 2
(3515 260);
DISPLAY 0.680851 (3515 260);
PAINT MONO (3515 260);
FORCEPROP 0 LASTPIN (3525 450) $PN AF81
J 2
(3515 460);
DISPLAY 0.680851 (3515 460);
PAINT MONO (3515 460);
FORCEPROP 0 LASTPIN (3525 500) $PN AF87
J 2
(3515 510);
DISPLAY 0.680851 (3515 510);
PAINT MONO (3515 510);
FORCEPROP 0 LASTPIN (3525 550) $PN AF91
J 2
(3515 560);
DISPLAY 0.680851 (3515 560);
PAINT MONO (3515 560);
FORCEPROP 0 LASTPIN (3525 600) $PN AG1
J 2
(3515 610);
DISPLAY 0.680851 (3515 610);
PAINT MONO (3515 610);
FORCEPROP 0 LASTPIN (3525 750) $PN AG13
J 2
(3515 760);
DISPLAY 0.680851 (3515 760);
PAINT MONO (3515 760);
FORCEPROP 0 LASTPIN (3525 800) $PN AG21
J 2
(3515 810);
DISPLAY 0.680851 (3515 810);
PAINT MONO (3515 810);
FORCEPROP 0 LASTPIN (3525 850) $PN AG27
J 2
(3515 860);
DISPLAY 0.680851 (3515 860);
PAINT MONO (3515 860);
FORCEPROP 0 LASTPIN (3525 900) $PN AG33
J 2
(3515 910);
DISPLAY 0.680851 (3515 910);
PAINT MONO (3515 910);
FORCEPROP 0 LASTPIN (3525 950) $PN AG39
J 2
(3515 960);
DISPLAY 0.680851 (3515 960);
PAINT MONO (3515 960);
FORCEPROP 0 LASTPIN (3525 1000) $PN AG45
J 2
(3515 1010);
DISPLAY 0.680851 (3515 1010);
PAINT MONO (3515 1010);
FORCEPROP 0 LASTPIN (3525 650) $PN AG5
J 2
(3515 660);
DISPLAY 0.680851 (3515 660);
PAINT MONO (3515 660);
FORCEPROP 0 LASTPIN (3525 1050) $PN AG52
J 2
(3515 1060);
DISPLAY 0.680851 (3515 1060);
PAINT MONO (3515 1060);
FORCEPROP 0 LASTPIN (3525 1100) $PN AG58
J 2
(3515 1110);
DISPLAY 0.680851 (3515 1110);
PAINT MONO (3515 1110);
FORCEPROP 0 LASTPIN (3525 1150) $PN AG64
J 2
(3515 1160);
DISPLAY 0.680851 (3515 1160);
PAINT MONO (3515 1160);
FORCEPROP 0 LASTPIN (3525 1200) $PN AG70
J 2
(3515 1210);
DISPLAY 0.680851 (3515 1210);
PAINT MONO (3515 1210);
FORCEPROP 0 LASTPIN (3525 1250) $PN AG76
J 2
(3515 1260);
DISPLAY 0.680851 (3515 1260);
PAINT MONO (3515 1260);
FORCEPROP 0 LASTPIN (3525 1300) $PN AG84
J 2
(3515 1310);
DISPLAY 0.680851 (3515 1310);
PAINT MONO (3515 1310);
FORCEPROP 0 LASTPIN (3525 1350) $PN AG88
J 2
(3515 1360);
DISPLAY 0.680851 (3515 1360);
PAINT MONO (3515 1360);
FORCEPROP 0 LASTPIN (3525 700) $PN AG9
J 2
(3515 710);
DISPLAY 0.680851 (3515 710);
PAINT MONO (3515 710);
FORCEPROP 0 LASTPIN (3525 1500) $PN AH12
J 2
(3515 1510);
DISPLAY 0.680851 (3515 1510);
PAINT MONO (3515 1510);
FORCEPROP 0 LASTPIN (3525 1550) $PN AH16
J 2
(3515 1560);
DISPLAY 0.680851 (3515 1560);
PAINT MONO (3515 1560);
FORCEPROP 0 LASTPIN (3525 1600) $PN AH20
J 2
(3515 1610);
DISPLAY 0.680851 (3515 1610);
PAINT MONO (3515 1610);
FORCEPROP 0 LASTPIN (3525 1650) $PN AH22
J 2
(3515 1660);
DISPLAY 0.680851 (3515 1660);
PAINT MONO (3515 1660);
FORCEPROP 0 LASTPIN (3525 1700) $PN AH26
J 2
(3515 1710);
DISPLAY 0.680851 (3515 1710);
PAINT MONO (3515 1710);
FORCEPROP 0 LASTPIN (3525 1750) $PN AH28
J 2
(3515 1760);
DISPLAY 0.680851 (3515 1760);
PAINT MONO (3515 1760);
FORCEPROP 0 LASTPIN (3525 1800) $PN AH32
J 2
(3515 1810);
DISPLAY 0.680851 (3515 1810);
PAINT MONO (3515 1810);
FORCEPROP 0 LASTPIN (3525 1850) $PN AH34
J 2
(3515 1860);
DISPLAY 0.680851 (3515 1860);
PAINT MONO (3515 1860);
FORCEPROP 0 LASTPIN (3525 1900) $PN AH38
J 2
(3515 1910);
DISPLAY 0.680851 (3515 1910);
PAINT MONO (3515 1910);
FORCEPROP 0 LASTPIN (3525 1400) $PN AH4
J 2
(3515 1410);
DISPLAY 0.680851 (3515 1410);
PAINT MONO (3515 1410);
FORCEPROP 0 LASTPIN (3525 1950) $PN AH40
J 2
(3515 1960);
DISPLAY 0.680851 (3515 1960);
PAINT MONO (3515 1960);
FORCEPROP 0 LASTPIN (3525 2000) $PN AH44
J 2
(3515 2010);
DISPLAY 0.680851 (3515 2010);
PAINT MONO (3515 2010);
FORCEPROP 0 LASTPIN (3525 2050) $PN AH47
J 2
(3515 2060);
DISPLAY 0.680851 (3515 2060);
PAINT MONO (3515 2060);
FORCEPROP 0 LASTPIN (3525 2100) $PN AH51
J 2
(3515 2110);
DISPLAY 0.680851 (3515 2110);
PAINT MONO (3515 2110);
FORCEPROP 0 LASTPIN (3525 2150) $PN AH53
J 2
(3515 2160);
DISPLAY 0.680851 (3515 2160);
PAINT MONO (3515 2160);
FORCEPROP 0 LASTPIN (3525 2200) $PN AH57
J 2
(3515 2210);
DISPLAY 0.680851 (3515 2210);
PAINT MONO (3515 2210);
FORCEPROP 0 LASTPIN (3525 2250) $PN AH59
J 2
(3515 2260);
DISPLAY 0.680851 (3515 2260);
PAINT MONO (3515 2260);
FORCEPROP 0 LASTPIN (3525 2300) $PN AH63
J 2
(3515 2310);
DISPLAY 0.680851 (3515 2310);
PAINT MONO (3515 2310);
FORCEPROP 0 LASTPIN (3525 2350) $PN AH65
J 2
(3515 2360);
DISPLAY 0.680851 (3515 2360);
PAINT MONO (3515 2360);
FORCEPROP 0 LASTPIN (3525 2400) $PN AH69
J 2
(3515 2410);
DISPLAY 0.680851 (3515 2410);
PAINT MONO (3515 2410);
FORCEPROP 0 LASTPIN (3525 2450) $PN AH71
J 2
(3515 2460);
DISPLAY 0.680851 (3515 2460);
PAINT MONO (3515 2460);
FORCEPROP 0 LASTPIN (3525 2500) $PN AH75
J 2
(3515 2510);
DISPLAY 0.680851 (3515 2510);
PAINT MONO (3515 2510);
FORCEPROP 0 LASTPIN (3525 2550) $PN AH77
J 2
(3515 2560);
DISPLAY 0.680851 (3515 2560);
PAINT MONO (3515 2560);
FORCEPROP 0 LASTPIN (3525 2600) $PN AH79
J 2
(3515 2610);
DISPLAY 0.680851 (3515 2610);
PAINT MONO (3515 2610);
FORCEPROP 0 LASTPIN (3525 1450) $PN AH8
J 2
(3515 1460);
DISPLAY 0.680851 (3515 1460);
PAINT MONO (3515 1460);
FORCEPROP 0 LASTPIN (3525 2650) $PN AH83
J 2
(3515 2660);
DISPLAY 0.680851 (3515 2660);
PAINT MONO (3515 2660);
FORCEPROP 0 LASTPIN (3525 2700) $PN AJ19
J 2
(3515 2710);
DISPLAY 0.680851 (3515 2710);
PAINT MONO (3515 2710);
FORCEPROP 0 LASTPIN (3525 2750) $PN AJ23
J 2
(3515 2760);
DISPLAY 0.680851 (3515 2760);
PAINT MONO (3515 2760);
FORCEPROP 0 LASTPIN (3525 2800) $PN AJ25
J 2
(3515 2810);
DISPLAY 0.680851 (3515 2810);
PAINT MONO (3515 2810);
FORCEPROP 0 LASTPIN (3525 2850) $PN AJ29
J 2
(3515 2860);
DISPLAY 0.680851 (3515 2860);
PAINT MONO (3515 2860);
FORCEPROP 0 LASTPIN (3525 2900) $PN AJ31
J 2
(3515 2910);
DISPLAY 0.680851 (3515 2910);
PAINT MONO (3515 2910);
FORCEPROP 0 LASTPIN (3525 2950) $PN AJ35
J 2
(3515 2960);
DISPLAY 0.680851 (3515 2960);
PAINT MONO (3515 2960);
FORCEPROP 0 LASTPIN (3525 3000) $PN AJ37
J 2
(3515 3010);
DISPLAY 0.680851 (3515 3010);
PAINT MONO (3515 3010);
FORCEPROP 0 LASTPIN (3525 3050) $PN AJ41
J 2
(3515 3060);
DISPLAY 0.680851 (3515 3060);
PAINT MONO (3515 3060);
FORCEPROP 0 LASTPIN (3525 3100) $PN AJ43
J 2
(3515 3110);
DISPLAY 0.680851 (3515 3110);
PAINT MONO (3515 3110);
FORCEPROP 0 LASTPIN (3525 3150) $PN AJ48
J 2
(3515 3160);
DISPLAY 0.680851 (3515 3160);
PAINT MONO (3515 3160);
FORCEPROP 0 LASTPIN (3525 3200) $PN AJ50
J 2
(3515 3210);
DISPLAY 0.680851 (3515 3210);
PAINT MONO (3515 3210);
FORCEPROP 0 LASTPIN (3525 3250) $PN AJ54
J 2
(3515 3260);
DISPLAY 0.680851 (3515 3260);
PAINT MONO (3515 3260);
FORCEPROP 0 LASTPIN (3525 3300) $PN AJ56
J 2
(3515 3310);
DISPLAY 0.680851 (3515 3310);
PAINT MONO (3515 3310);
FORCEPROP 0 LASTPIN (3525 3350) $PN AJ60
J 2
(3515 3360);
DISPLAY 0.680851 (3515 3360);
PAINT MONO (3515 3360);
FORCEPROP 0 LASTPIN (3525 3400) $PN AJ62
J 2
(3515 3410);
DISPLAY 0.680851 (3515 3410);
PAINT MONO (3515 3410);
FORCEPROP 0 LASTPIN (3525 3450) $PN AJ66
J 2
(3515 3460);
DISPLAY 0.680851 (3515 3460);
PAINT MONO (3515 3460);
FORCEPROP 0 LASTPIN (3525 3500) $PN AJ68
J 2
(3515 3510);
DISPLAY 0.680851 (3515 3510);
PAINT MONO (3515 3510);
FORCEPROP 0 LASTPIN (3525 3550) $PN AJ72
J 2
(3515 3560);
DISPLAY 0.680851 (3515 3560);
PAINT MONO (3515 3560);
FORCEPROP 0 LASTPIN (3525 3600) $PN AJ74
J 2
(3515 3610);
DISPLAY 0.680851 (3515 3610);
PAINT MONO (3515 3610);
FORCEPROP 0 LASTPIN (3525 3650) $PN AJ78
J 2
(3515 3660);
DISPLAY 0.680851 (3515 3660);
PAINT MONO (3515 3660);
FORCEPROP 0 LASTPIN (3525 3700) $PN AJ84
J 2
(3515 3710);
DISPLAY 0.680851 (3515 3710);
PAINT MONO (3515 3710);
FORCEPROP 0 LASTPIN (3525 3750) $PN AJ88
J 2
(3515 3760);
DISPLAY 0.680851 (3515 3760);
PAINT MONO (3515 3760);
FORCEPROP 2 LAST CDS_LIB pure_quanta
J 0
(4725 1775);
DISPLAY INVISIBLE (4725 1775);
FORCEPROP 1 LAST NEEDS_NO_SIZE TRUE
J 0
(4725 1775);
DISPLAY 0.723404 (4725 1775);
PAINT GREEN (4725 1775);
DISPLAY INVISIBLE (4725 1775);
FORCEPROP 1 LAST CDS_LMAN_SYM_OUTLINE -1050,2150,1050,-2100
J 0
(4725 1775);
DISPLAY 0.468085 (4725 1775);
PAINT GREEN (4725 1775);
DISPLAY INVISIBLE (4725 1775);
FORCEPROP 0 LAST CDS_LOCATION U1
J 0
(3675 4250);
DISPLAY 1.021277 (3675 4250);
DISPLAY INVISIBLE (3675 4250);
FORCEPROP 0 LAST $SEC 39
J 0
(3675 4250);
DISPLAY 0.680851 (3675 4250);
PAINT MONO (3675 4250);
DISPLAY INVISIBLE (3675 4250);
FORCEPROP 2 LAST CDS_SEC 39
J 0
(3675 4250);
DISPLAY 1.021277 (3675 4250);
DISPLAY INVISIBLE (3675 4250);
FORCEPROP 1 LAST PATH I8
J 0
(4725 1775);
DISPLAY 0.723404 (4725 1775);
PAINT GREEN (4725 1775);
DISPLAY INVISIBLE (4725 1775);
FORCEADD UNIVERSAL_GND..1
(6175 -750);
FORCEPROP 3 LASTPIN (6175 -700) SIG_NAME GND\g
J 0
(6185 -690);
DISPLAY 0.659574 (6185 -690);
PAINT MONO (6185 -690);
DISPLAY INVISIBLE (6185 -690);
FORCEPROP 2 LAST CDS_LIB logical_power
J 0
(6175 -750);
PAINT MONO (6175 -750);
DISPLAY INVISIBLE (6175 -750);
FORCEPROP 1 LAST HDL_POWER GND
J 1
(6200 -825);
DISPLAY 0.872340 (6200 -825);
PAINT GREEN (6200 -825);
DISPLAY INVISIBLE (6200 -825);
FORCEPROP 1 LAST PATH I9
J 0
(6250 -750);
DISPLAY 0.872340 (6250 -750);
PAINT AQUA (6250 -750);
DISPLAY INVISIBLE (6250 -750);
FORCEADD QUANTA_TITLE_BLOCK_C..1
(6375 -1600);
FORCEPROP 0 LAST CDS_CON_LAST_MODIFIED Fri Aug 25 14:00:53 2023
J 0
(4490 -1585);
PAINT MONO (4490 -1585);
DISPLAY INVISIBLE (4490 -1585);
FORCEPROP 1 LAST CUSTOM_TXT_CDS <CON_LAST_MODIFIED>
J 0
(4490 -1585);
DISPLAY 0.978723 (4490 -1585);
FORCEPROP 2 LAST CUSTOM_TXT_CDS <XR_PAGE_TITLE>
J 0
(-1515 3650);
DISPLAY 0.638298 (-1515 3650);
PAINT PINK (-1515 3650);
DISPLAY INVISIBLE (-1515 3650);
FORCEPROP 2 LAST CUSTOM_TXT_CDS <Q_NUMBER>
J 0
(4972 -1497);
DISPLAY 1.212766 (4972 -1497);
FORCEPROP 1 LAST CUSTOM_TXT_CDS <NAME_2>
J 0
(3200 -1550);
FORCEPROP 1 LAST CUSTOM_TXT_CDS <NAME_1>
J 0
(3200 -1425);
FORCEPROP 1 LAST CUSTOM_TXT_CDS <Q_PROJ>
J 0
(3993 -1498);
DISPLAY 1.212766 (3993 -1498);
FORCEPROP 1 LAST CUSTOM_TXT_CDS <Q_REV>
J 0
(6191 -1497);
DISPLAY 1.212766 (6191 -1497);
FORCEPROP 1 LAST CUSTOM_TXT_CDS <CON_PAGE_NUM> OF <CON_TOTAL_PAGES>
J 0
(5929 -1582);
DISPLAY 0.978723 (5929 -1582);
FORCEPROP 1 LAST Q_TITLE SPR CPU1 POWER - GND (29 OF 30)
J 0
(-2991 -1574);
DISPLAY 1.957447 (-2991 -1574);
PAINT GREEN (-2991 -1574);
FORCEPROP 1 LAST Q_DEPT 
J 1
(2612 -1551);
DISPLAY 1.957447 (2612 -1551);
PAINT GREEN (2612 -1551);
FORCEPROP 1 LAST COMMENT_BODY TRUE
J 0
(6387 -1613);
DISPLAY 0.978723 (6387 -1613);
PAINT GREEN (6387 -1613);
DISPLAY INVISIBLE (6387 -1613);
FORCEPROP 2 LAST CDS_XR_PAGE_TITLE CR-72 : @S9S_MB_2U_LIB.S9S_MB_2U(SCH_1):PAGE72
J 0
(-1515 3650);
DISPLAY 0.638298 (-1515 3650);
PAINT PINK (-1515 3650);
DISPLAY INVISIBLE (-1515 3650);
FORCEPROP 2 LAST PAGE_BORDER TRUE
J 0
(-1515 3650);
DISPLAY 0.638298 (-1515 3650);
PAINT PINK (-1515 3650);
DISPLAY INVISIBLE (-1515 3650);
FORCEPROP 1 LAST CDS_LMAN_SYM_OUTLINE -9475,6775,100,-125
J 0
(6375 -1600);
DISPLAY 0.468085 (6375 -1600);
PAINT GREEN (6375 -1600);
DISPLAY INVISIBLE (6375 -1600);
FORCEPROP 2 LAST CDS_LIB pure_quanta
J 0
(6375 -1600);
PAINT MONO (6375 -1600);
DISPLAY INVISIBLE (6375 -1600);
WIRE 16 -1 (6175 -200)(6175 -700);
WIRE 16 -1 (6175 -150)(6175 -200);
WIRE 16 -1 (5925 -200)(6175 -200);
WIRE 16 -1 (3275 -200)(3275 -700);
WIRE 16 -1 (3275 -150)(3275 -200);
WIRE 16 -1 (3275 -200)(3525 -200);
WIRE 16 -1 (3150 -200)(3150 -700);
WIRE 16 -1 (3150 -150)(3150 -200);
WIRE 16 -1 (2900 -200)(3150 -200);
WIRE 16 -1 (250 -200)(250 -700);
WIRE 16 -1 (250 -150)(250 -200);
WIRE 16 -1 (250 -200)(500 -200);
WIRE 16 -1 (100 -200)(100 -700);
WIRE 16 -1 (100 -150)(100 -200);
WIRE 16 -1 (-150 -200)(100 -200);
WIRE 16 -1 (-2800 -200)(-2800 -700);
WIRE 16 -1 (-2800 -150)(-2800 -200);
WIRE 16 -1 (-2800 -200)(-2550 -200);
WIRE 16 -1 (3150 3750)(2900 3750);
WIRE 16 -1 (3150 3700)(2900 3700);
WIRE 16 -1 (3150 3750)(3150 3700);
WIRE 16 -1 (3150 3650)(2900 3650);
WIRE 16 -1 (3150 3700)(3150 3650);
WIRE 16 -1 (3150 3600)(2900 3600);
WIRE 16 -1 (3150 3650)(3150 3600);
WIRE 16 -1 (2900 3550)(3150 3550);
WIRE 16 -1 (3150 3550)(3150 3600);
WIRE 16 -1 (3150 3500)(2900 3500);
WIRE 16 -1 (3150 3500)(3150 3550);
WIRE 16 -1 (3150 3450)(2900 3450);
WIRE 16 -1 (3150 3500)(3150 3450);
WIRE 16 -1 (3150 3400)(2900 3400);
WIRE 16 -1 (3150 3450)(3150 3400);
WIRE 16 -1 (3150 3350)(2900 3350);
WIRE 16 -1 (3150 3400)(3150 3350);
WIRE 16 -1 (3150 3300)(2900 3300);
WIRE 16 -1 (3150 3350)(3150 3300);
WIRE 16 -1 (3150 3250)(2900 3250);
WIRE 16 -1 (3150 3300)(3150 3250);
WIRE 16 -1 (3150 3200)(2900 3200);
WIRE 16 -1 (3150 3250)(3150 3200);
WIRE 16 -1 (3150 3150)(2900 3150);
WIRE 16 -1 (3150 3200)(3150 3150);
WIRE 16 -1 (3150 3100)(2900 3100);
WIRE 16 -1 (3150 3150)(3150 3100);
WIRE 16 -1 (2900 3050)(3150 3050);
WIRE 16 -1 (3150 3100)(3150 3050);
WIRE 16 -1 (2900 3000)(3150 3000);
WIRE 16 -1 (3150 3050)(3150 3000);
WIRE 16 -1 (2900 2950)(3150 2950);
WIRE 16 -1 (3150 3000)(3150 2950);
WIRE 16 -1 (2900 2900)(3150 2900);
WIRE 16 -1 (3150 2950)(3150 2900);
WIRE 16 -1 (2900 2850)(3150 2850);
WIRE 16 -1 (3150 2900)(3150 2850);
WIRE 16 -1 (2900 2800)(3150 2800);
WIRE 16 -1 (3150 2850)(3150 2800);
WIRE 16 -1 (2900 2750)(3150 2750);
WIRE 16 -1 (3150 2800)(3150 2750);
WIRE 16 -1 (2900 2700)(3150 2700);
WIRE 16 -1 (3150 2700)(3150 2750);
WIRE 16 -1 (2900 2650)(3150 2650);
WIRE 16 -1 (3150 2700)(3150 2650);
WIRE 16 -1 (3150 2600)(2900 2600);
WIRE 16 -1 (3150 2650)(3150 2600);
WIRE 16 -1 (3150 2550)(2900 2550);
WIRE 16 -1 (3150 2600)(3150 2550);
WIRE 16 -1 (3150 2500)(2900 2500);
WIRE 16 -1 (3150 2550)(3150 2500);
WIRE 16 -1 (3150 2450)(2900 2450);
WIRE 16 -1 (3150 2500)(3150 2450);
WIRE 16 -1 (2900 2400)(3150 2400);
WIRE 16 -1 (3150 2400)(3150 2450);
WIRE 16 -1 (3150 2350)(2900 2350);
WIRE 16 -1 (3150 2350)(3150 2400);
WIRE 16 -1 (3150 2300)(2900 2300);
WIRE 16 -1 (3150 2350)(3150 2300);
WIRE 16 -1 (3150 2250)(2900 2250);
WIRE 16 -1 (3150 2300)(3150 2250);
WIRE 16 -1 (3150 2200)(2900 2200);
WIRE 16 -1 (3150 2250)(3150 2200);
WIRE 16 -1 (3150 2150)(2900 2150);
WIRE 16 -1 (3150 2200)(3150 2150);
WIRE 16 -1 (3150 2100)(2900 2100);
WIRE 16 -1 (3150 2150)(3150 2100);
WIRE 16 -1 (3150 2050)(2900 2050);
WIRE 16 -1 (3150 2100)(3150 2050);
WIRE 16 -1 (3150 2000)(2900 2000);
WIRE 16 -1 (3150 2050)(3150 2000);
WIRE 16 -1 (3150 1950)(2900 1950);
WIRE 16 -1 (3150 2000)(3150 1950);
WIRE 16 -1 (2900 1900)(3150 1900);
WIRE 16 -1 (3150 1950)(3150 1900);
WIRE 16 -1 (2900 1850)(3150 1850);
WIRE 16 -1 (3150 1900)(3150 1850);
WIRE 16 -1 (2900 1800)(3150 1800);
WIRE 16 -1 (3150 1850)(3150 1800);
WIRE 16 -1 (2900 1750)(3150 1750);
WIRE 16 -1 (3150 1800)(3150 1750);
WIRE 16 -1 (2900 1700)(3150 1700);
WIRE 16 -1 (3150 1750)(3150 1700);
WIRE 16 -1 (2900 1650)(3150 1650);
WIRE 16 -1 (3150 1700)(3150 1650);
WIRE 16 -1 (2900 1600)(3150 1600);
WIRE 16 -1 (3150 1650)(3150 1600);
WIRE 16 -1 (2900 1550)(3150 1550);
WIRE 16 -1 (3150 1550)(3150 1600);
WIRE 16 -1 (2900 1500)(3150 1500);
WIRE 16 -1 (3150 1550)(3150 1500);
WIRE 16 -1 (3150 1450)(2900 1450);
WIRE 16 -1 (3150 1500)(3150 1450);
WIRE 16 -1 (3150 1400)(2900 1400);
WIRE 16 -1 (3150 1450)(3150 1400);
WIRE 16 -1 (3150 1350)(2900 1350);
WIRE 16 -1 (3150 1400)(3150 1350);
WIRE 16 -1 (3150 1300)(2900 1300);
WIRE 16 -1 (3150 1350)(3150 1300);
WIRE 16 -1 (2900 1250)(3150 1250);
WIRE 16 -1 (3150 1250)(3150 1300);
WIRE 16 -1 (3150 1200)(2900 1200);
WIRE 16 -1 (3150 1200)(3150 1250);
WIRE 16 -1 (3150 1150)(2900 1150);
WIRE 16 -1 (3150 1200)(3150 1150);
WIRE 16 -1 (3150 1100)(2900 1100);
WIRE 16 -1 (3150 1150)(3150 1100);
WIRE 16 -1 (2900 1050)(3150 1050);
WIRE 16 -1 (3150 1100)(3150 1050);
WIRE 16 -1 (2900 1000)(3150 1000);
WIRE 16 -1 (3150 1050)(3150 1000);
WIRE 16 -1 (2900 950)(3150 950);
WIRE 16 -1 (3150 1000)(3150 950);
WIRE 16 -1 (2900 900)(3150 900);
WIRE 16 -1 (3150 950)(3150 900);
WIRE 16 -1 (2900 850)(3150 850);
WIRE 16 -1 (3150 900)(3150 850);
WIRE 16 -1 (2900 800)(3150 800);
WIRE 16 -1 (3150 850)(3150 800);
WIRE 16 -1 (2900 750)(3150 750);
WIRE 16 -1 (3150 800)(3150 750);
WIRE 16 -1 (2900 700)(3150 700);
WIRE 16 -1 (3150 700)(3150 750);
WIRE 16 -1 (2900 650)(3150 650);
WIRE 16 -1 (3150 700)(3150 650);
WIRE 16 -1 (3150 600)(2900 600);
WIRE 16 -1 (3150 650)(3150 600);
WIRE 16 -1 (3150 550)(2900 550);
WIRE 16 -1 (3150 600)(3150 550);
WIRE 16 -1 (3150 500)(2900 500);
WIRE 16 -1 (3150 550)(3150 500);
WIRE 16 -1 (3150 450)(2900 450);
WIRE 16 -1 (3150 500)(3150 450);
WIRE 16 -1 (2900 400)(3150 400);
WIRE 16 -1 (3150 400)(3150 450);
WIRE 16 -1 (3150 350)(2900 350);
WIRE 16 -1 (3150 350)(3150 400);
WIRE 16 -1 (3150 300)(2900 300);
WIRE 16 -1 (3150 350)(3150 300);
WIRE 16 -1 (3150 250)(2900 250);
WIRE 16 -1 (3150 300)(3150 250);
WIRE 16 -1 (2900 200)(3150 200);
WIRE 16 -1 (3150 250)(3150 200);
WIRE 16 -1 (2900 150)(3150 150);
WIRE 16 -1 (3150 200)(3150 150);
WIRE 16 -1 (2900 100)(3150 100);
WIRE 16 -1 (3150 150)(3150 100);
WIRE 16 -1 (2900 50)(3150 50);
WIRE 16 -1 (3150 100)(3150 50);
WIRE 16 -1 (3150 50)(3150 0);
WIRE 16 -1 (2900 0)(3150 0);
WIRE 16 -1 (2900 -50)(3150 -50);
WIRE 16 -1 (3150 0)(3150 -50);
WIRE 16 -1 (2900 -100)(3150 -100);
WIRE 16 -1 (3150 -50)(3150 -100);
WIRE 16 -1 (3150 -150)(3150 -100);
WIRE 16 -1 (2900 -150)(3150 -150);
WIRE 16 -1 (3525 3750)(3275 3750);
WIRE 16 -1 (3275 3750)(3275 3700);
WIRE 16 -1 (3525 3700)(3275 3700);
WIRE 16 -1 (3275 3700)(3275 3650);
WIRE 16 -1 (3525 3650)(3275 3650);
WIRE 16 -1 (3275 3650)(3275 3600);
WIRE 16 -1 (3525 3600)(3275 3600);
WIRE 16 -1 (3525 3550)(3275 3550);
WIRE 16 -1 (3275 3600)(3275 3550);
WIRE 16 -1 (3275 3550)(3275 3500);
WIRE 16 -1 (3525 3500)(3275 3500);
WIRE 16 -1 (3275 3500)(3275 3450);
WIRE 16 -1 (3525 3450)(3275 3450);
WIRE 16 -1 (3275 3450)(3275 3400);
WIRE 16 -1 (3525 3400)(3275 3400);
WIRE 16 -1 (3275 3400)(3275 3350);
WIRE 16 -1 (3525 3350)(3275 3350);
WIRE 16 -1 (3275 3350)(3275 3300);
WIRE 16 -1 (3525 3300)(3275 3300);
WIRE 16 -1 (3275 3300)(3275 3250);
WIRE 16 -1 (3525 3250)(3275 3250);
WIRE 16 -1 (3275 3250)(3275 3200);
WIRE 16 -1 (3525 3200)(3275 3200);
WIRE 16 -1 (3275 3200)(3275 3150);
WIRE 16 -1 (3525 3150)(3275 3150);
WIRE 16 -1 (3275 3150)(3275 3100);
WIRE 16 -1 (3525 3100)(3275 3100);
WIRE 16 -1 (3275 3050)(3525 3050);
WIRE 16 -1 (3275 3100)(3275 3050);
WIRE 16 -1 (3275 3050)(3275 3000);
WIRE 16 -1 (3275 3000)(3525 3000);
WIRE 16 -1 (3275 3000)(3275 2950);
WIRE 16 -1 (3275 2950)(3525 2950);
WIRE 16 -1 (3275 2950)(3275 2900);
WIRE 16 -1 (3275 2900)(3525 2900);
WIRE 16 -1 (3275 2900)(3275 2850);
WIRE 16 -1 (3275 2850)(3525 2850);
WIRE 16 -1 (3275 2850)(3275 2800);
WIRE 16 -1 (3275 2800)(3525 2800);
WIRE 16 -1 (3275 2800)(3275 2750);
WIRE 16 -1 (3275 2750)(3525 2750);
WIRE 16 -1 (3275 2750)(3275 2700);
WIRE 16 -1 (3275 2700)(3525 2700);
WIRE 16 -1 (3275 2700)(3275 2650);
WIRE 16 -1 (3275 2650)(3525 2650);
WIRE 16 -1 (3275 2650)(3275 2600);
WIRE 16 -1 (3275 2600)(3525 2600);
WIRE 16 -1 (3275 2550)(3525 2550);
WIRE 16 -1 (3275 2600)(3275 2550);
WIRE 16 -1 (3275 2550)(3275 2500);
WIRE 16 -1 (3275 2500)(3525 2500);
WIRE 16 -1 (3275 2500)(3275 2450);
WIRE 16 -1 (3275 2450)(3525 2450);
WIRE 16 -1 (3275 2450)(3275 2400);
WIRE 16 -1 (3275 2400)(3525 2400);
WIRE 16 -1 (3275 2400)(3275 2350);
WIRE 16 -1 (3275 2350)(3525 2350);
WIRE 16 -1 (3275 2350)(3275 2300);
WIRE 16 -1 (3275 2300)(3525 2300);
WIRE 16 -1 (3275 2300)(3275 2250);
WIRE 16 -1 (3275 2250)(3525 2250);
WIRE 16 -1 (3275 2250)(3275 2200);
WIRE 16 -1 (3275 2200)(3525 2200);
WIRE 16 -1 (3275 2200)(3275 2150);
WIRE 16 -1 (3275 2150)(3525 2150);
WIRE 16 -1 (3275 2150)(3275 2100);
WIRE 16 -1 (3275 2100)(3525 2100);
WIRE 16 -1 (3275 2100)(3275 2050);
WIRE 16 -1 (3275 2050)(3525 2050);
WIRE 16 -1 (3275 2000)(3525 2000);
WIRE 16 -1 (3275 2050)(3275 2000);
WIRE 16 -1 (3275 2000)(3275 1950);
WIRE 16 -1 (3275 1950)(3525 1950);
WIRE 16 -1 (3275 1950)(3275 1900);
WIRE 16 -1 (3275 1900)(3525 1900);
WIRE 16 -1 (3275 1900)(3275 1850);
WIRE 16 -1 (3275 1850)(3525 1850);
WIRE 16 -1 (3275 1850)(3275 1800);
WIRE 16 -1 (3275 1800)(3525 1800);
WIRE 16 -1 (3275 1800)(3275 1750);
WIRE 16 -1 (3275 1750)(3525 1750);
WIRE 16 -1 (3275 1750)(3275 1700);
WIRE 16 -1 (3525 1700)(3275 1700);
WIRE 16 -1 (3275 1700)(3275 1650);
WIRE 16 -1 (3275 1650)(3525 1650);
WIRE 16 -1 (3275 1650)(3275 1600);
WIRE 16 -1 (3275 1600)(3525 1600);
WIRE 16 -1 (3275 1600)(3275 1550);
WIRE 16 -1 (3275 1550)(3525 1550);
WIRE 16 -1 (3275 1500)(3525 1500);
WIRE 16 -1 (3275 1550)(3275 1500);
WIRE 16 -1 (3275 1500)(3275 1450);
WIRE 16 -1 (3275 1450)(3525 1450);
WIRE 16 -1 (3275 1450)(3275 1400);
WIRE 16 -1 (3275 1400)(3525 1400);
WIRE 16 -1 (3275 1400)(3275 1350);
WIRE 16 -1 (3275 1350)(3525 1350);
WIRE 16 -1 (3275 1350)(3275 1300);
WIRE 16 -1 (3275 1300)(3525 1300);
WIRE 16 -1 (3275 1300)(3275 1250);
WIRE 16 -1 (3275 1250)(3525 1250);
WIRE 16 -1 (3275 1250)(3275 1200);
WIRE 16 -1 (3275 1200)(3525 1200);
WIRE 16 -1 (3275 1200)(3275 1150);
WIRE 16 -1 (3275 1150)(3525 1150);
WIRE 16 -1 (3275 1150)(3275 1100);
WIRE 16 -1 (3275 1100)(3525 1100);
WIRE 16 -1 (3275 1100)(3275 1050);
WIRE 16 -1 (3275 1050)(3525 1050);
WIRE 16 -1 (3275 1000)(3525 1000);
WIRE 16 -1 (3275 1050)(3275 1000);
WIRE 16 -1 (3275 1000)(3275 950);
WIRE 16 -1 (3275 950)(3525 950);
WIRE 16 -1 (3275 950)(3275 900);
WIRE 16 -1 (3275 900)(3525 900);
WIRE 16 -1 (3275 900)(3275 850);
WIRE 16 -1 (3275 850)(3525 850);
WIRE 16 -1 (3275 850)(3275 800);
WIRE 16 -1 (3275 800)(3525 800);
WIRE 16 -1 (3275 800)(3275 750);
WIRE 16 -1 (3275 750)(3525 750);
WIRE 16 -1 (3275 750)(3275 700);
WIRE 16 -1 (3525 700)(3275 700);
WIRE 16 -1 (3275 700)(3275 650);
WIRE 16 -1 (3275 650)(3525 650);
WIRE 16 -1 (3275 650)(3275 600);
WIRE 16 -1 (3275 600)(3525 600);
WIRE 16 -1 (3275 600)(3275 550);
WIRE 16 -1 (3275 550)(3525 550);
WIRE 16 -1 (3275 500)(3525 500);
WIRE 16 -1 (3275 550)(3275 500);
WIRE 16 -1 (3275 500)(3275 450);
WIRE 16 -1 (3275 450)(3525 450);
WIRE 16 -1 (3275 450)(3275 400);
WIRE 16 -1 (3525 400)(3275 400);
WIRE 16 -1 (3275 400)(3275 350);
WIRE 16 -1 (3275 350)(3525 350);
WIRE 16 -1 (3275 350)(3275 300);
WIRE 16 -1 (3275 300)(3525 300);
WIRE 16 -1 (3275 300)(3275 250);
WIRE 16 -1 (3275 250)(3525 250);
WIRE 16 -1 (3275 250)(3275 200);
WIRE 16 -1 (3275 200)(3525 200);
WIRE 16 -1 (3275 200)(3275 150);
WIRE 16 -1 (3275 150)(3525 150);
WIRE 16 -1 (3275 150)(3275 100);
WIRE 16 -1 (3275 100)(3525 100);
WIRE 16 -1 (3275 100)(3275 50);
WIRE 16 -1 (3525 50)(3275 50);
WIRE 16 -1 (3275 50)(3275 0);
WIRE 16 -1 (3275 0)(3525 0);
WIRE 16 -1 (3275 -50)(3525 -50);
WIRE 16 -1 (3275 0)(3275 -50);
WIRE 16 -1 (3275 -50)(3275 -100);
WIRE 16 -1 (3275 -100)(3525 -100);
WIRE 16 -1 (3275 -100)(3275 -150);
WIRE 16 -1 (3275 -150)(3525 -150);
WIRE 16 -1 (-2550 3750)(-2800 3750);
WIRE 16 -1 (-2800 3750)(-2800 3700);
WIRE 16 -1 (-2550 3700)(-2800 3700);
WIRE 16 -1 (-2800 3700)(-2800 3650);
WIRE 16 -1 (-2550 3650)(-2800 3650);
WIRE 16 -1 (-2800 3650)(-2800 3600);
WIRE 16 -1 (-2550 3600)(-2800 3600);
WIRE 16 -1 (-2800 3600)(-2800 3550);
WIRE 16 -1 (-2550 3550)(-2800 3550);
WIRE 16 -1 (-2800 3550)(-2800 3500);
WIRE 16 -1 (-2550 3500)(-2800 3500);
WIRE 16 -1 (-2800 3500)(-2800 3450);
WIRE 16 -1 (-2550 3450)(-2800 3450);
WIRE 16 -1 (-2800 3450)(-2800 3400);
WIRE 16 -1 (-2550 3400)(-2800 3400);
WIRE 16 -1 (-2800 3400)(-2800 3350);
WIRE 16 -1 (-2550 3350)(-2800 3350);
WIRE 16 -1 (-2800 3350)(-2800 3300);
WIRE 16 -1 (-2550 3300)(-2800 3300);
WIRE 16 -1 (-2800 3300)(-2800 3250);
WIRE 16 -1 (-2550 3250)(-2800 3250);
WIRE 16 -1 (-2800 3250)(-2800 3200);
WIRE 16 -1 (-2550 3200)(-2800 3200);
WIRE 16 -1 (-2800 3200)(-2800 3150);
WIRE 16 -1 (-2550 3150)(-2800 3150);
WIRE 16 -1 (-2800 3150)(-2800 3100);
WIRE 16 -1 (-2550 3100)(-2800 3100);
WIRE 16 -1 (-2800 3050)(-2550 3050);
WIRE 16 -1 (-2800 3100)(-2800 3050);
WIRE 16 -1 (-2800 3050)(-2800 3000);
WIRE 16 -1 (-2800 3000)(-2550 3000);
WIRE 16 -1 (-2800 3000)(-2800 2950);
WIRE 16 -1 (-2800 2950)(-2550 2950);
WIRE 16 -1 (-2800 2950)(-2800 2900);
WIRE 16 -1 (-2800 2900)(-2550 2900);
WIRE 16 -1 (-2800 2900)(-2800 2850);
WIRE 16 -1 (-2800 2850)(-2550 2850);
WIRE 16 -1 (-2800 2850)(-2800 2800);
WIRE 16 -1 (-2800 2800)(-2550 2800);
WIRE 16 -1 (-2800 2800)(-2800 2750);
WIRE 16 -1 (-2800 2750)(-2550 2750);
WIRE 16 -1 (-2800 2750)(-2800 2700);
WIRE 16 -1 (-2800 2700)(-2550 2700);
WIRE 16 -1 (-2800 2700)(-2800 2650);
WIRE 16 -1 (-2800 2650)(-2550 2650);
WIRE 16 -1 (-2800 2650)(-2800 2600);
WIRE 16 -1 (-2800 2600)(-2550 2600);
WIRE 16 -1 (-2800 2600)(-2800 2550);
WIRE 16 -1 (-2800 2550)(-2550 2550);
WIRE 16 -1 (-2800 2550)(-2800 2500);
WIRE 16 -1 (-2800 2500)(-2550 2500);
WIRE 16 -1 (-2800 2500)(-2800 2450);
WIRE 16 -1 (-2800 2450)(-2550 2450);
WIRE 16 -1 (-2800 2450)(-2800 2400);
WIRE 16 -1 (-2800 2400)(-2550 2400);
WIRE 16 -1 (-2800 2400)(-2800 2350);
WIRE 16 -1 (-2800 2350)(-2550 2350);
WIRE 16 -1 (-2800 2350)(-2800 2300);
WIRE 16 -1 (-2800 2300)(-2550 2300);
WIRE 16 -1 (-2800 2300)(-2800 2250);
WIRE 16 -1 (-2800 2250)(-2550 2250);
WIRE 16 -1 (-2800 2250)(-2800 2200);
WIRE 16 -1 (-2800 2200)(-2550 2200);
WIRE 16 -1 (-2800 2200)(-2800 2150);
WIRE 16 -1 (-2800 2150)(-2550 2150);
WIRE 16 -1 (-2800 2150)(-2800 2100);
WIRE 16 -1 (-2800 2100)(-2550 2100);
WIRE 16 -1 (-2800 2100)(-2800 2050);
WIRE 16 -1 (-2800 2050)(-2550 2050);
WIRE 16 -1 (-2800 2000)(-2550 2000);
WIRE 16 -1 (-2800 2050)(-2800 2000);
WIRE 16 -1 (-2800 2000)(-2800 1950);
WIRE 16 -1 (-2800 1950)(-2550 1950);
WIRE 16 -1 (-2800 1950)(-2800 1900);
WIRE 16 -1 (-2800 1900)(-2550 1900);
WIRE 16 -1 (-2800 1900)(-2800 1850);
WIRE 16 -1 (-2800 1850)(-2550 1850);
WIRE 16 -1 (-2800 1850)(-2800 1800);
WIRE 16 -1 (-2800 1800)(-2550 1800);
WIRE 16 -1 (-2800 1800)(-2800 1750);
WIRE 16 -1 (-2800 1750)(-2550 1750);
WIRE 16 -1 (-2800 1750)(-2800 1700);
WIRE 16 -1 (-2550 1700)(-2800 1700);
WIRE 16 -1 (-2800 1700)(-2800 1650);
WIRE 16 -1 (-2800 1650)(-2550 1650);
WIRE 16 -1 (-2800 1650)(-2800 1600);
WIRE 16 -1 (-2800 1600)(-2550 1600);
WIRE 16 -1 (-2800 1600)(-2800 1550);
WIRE 16 -1 (-2800 1550)(-2550 1550);
WIRE 16 -1 (-2800 1550)(-2800 1500);
WIRE 16 -1 (-2800 1500)(-2550 1500);
WIRE 16 -1 (-2800 1500)(-2800 1450);
WIRE 16 -1 (-2800 1450)(-2550 1450);
WIRE 16 -1 (-2800 1450)(-2800 1400);
WIRE 16 -1 (-2800 1400)(-2550 1400);
WIRE 16 -1 (-2800 1400)(-2800 1350);
WIRE 16 -1 (-2800 1350)(-2550 1350);
WIRE 16 -1 (-2800 1350)(-2800 1300);
WIRE 16 -1 (-2800 1300)(-2550 1300);
WIRE 16 -1 (-2800 1300)(-2800 1250);
WIRE 16 -1 (-2800 1250)(-2550 1250);
WIRE 16 -1 (-2800 1250)(-2800 1200);
WIRE 16 -1 (-2800 1200)(-2550 1200);
WIRE 16 -1 (-2800 1200)(-2800 1150);
WIRE 16 -1 (-2800 1150)(-2550 1150);
WIRE 16 -1 (-2800 1150)(-2800 1100);
WIRE 16 -1 (-2800 1100)(-2550 1100);
WIRE 16 -1 (-2800 1100)(-2800 1050);
WIRE 16 -1 (-2800 1050)(-2550 1050);
WIRE 16 -1 (-2800 1000)(-2550 1000);
WIRE 16 -1 (-2800 1050)(-2800 1000);
WIRE 16 -1 (-2800 1000)(-2800 950);
WIRE 16 -1 (-2800 950)(-2550 950);
WIRE 16 -1 (-2800 950)(-2800 900);
WIRE 16 -1 (-2800 900)(-2550 900);
WIRE 16 -1 (-2800 900)(-2800 850);
WIRE 16 -1 (-2800 850)(-2550 850);
WIRE 16 -1 (-2800 850)(-2800 800);
WIRE 16 -1 (-2800 800)(-2550 800);
WIRE 16 -1 (-2800 800)(-2800 750);
WIRE 16 -1 (-2800 750)(-2550 750);
WIRE 16 -1 (-2800 750)(-2800 700);
WIRE 16 -1 (-2550 700)(-2800 700);
WIRE 16 -1 (-2800 700)(-2800 650);
WIRE 16 -1 (-2800 650)(-2550 650);
WIRE 16 -1 (-2800 650)(-2800 600);
WIRE 16 -1 (-2800 600)(-2550 600);
WIRE 16 -1 (-2800 600)(-2800 550);
WIRE 16 -1 (-2800 550)(-2550 550);
WIRE 16 -1 (-2800 550)(-2800 500);
WIRE 16 -1 (-2800 500)(-2550 500);
WIRE 16 -1 (-2800 500)(-2800 450);
WIRE 16 -1 (-2800 450)(-2550 450);
WIRE 16 -1 (-2800 450)(-2800 400);
WIRE 16 -1 (-2550 400)(-2800 400);
WIRE 16 -1 (-2800 400)(-2800 350);
WIRE 16 -1 (-2800 350)(-2550 350);
WIRE 16 -1 (-2800 350)(-2800 300);
WIRE 16 -1 (-2800 300)(-2550 300);
WIRE 16 -1 (-2800 300)(-2800 250);
WIRE 16 -1 (-2800 250)(-2550 250);
WIRE 16 -1 (-2800 250)(-2800 200);
WIRE 16 -1 (-2800 200)(-2550 200);
WIRE 16 -1 (-2800 200)(-2800 150);
WIRE 16 -1 (-2800 150)(-2550 150);
WIRE 16 -1 (-2800 150)(-2800 100);
WIRE 16 -1 (-2800 100)(-2550 100);
WIRE 16 -1 (-2800 100)(-2800 50);
WIRE 16 -1 (-2550 50)(-2800 50);
WIRE 16 -1 (-2800 50)(-2800 0);
WIRE 16 -1 (-2800 0)(-2550 0);
WIRE 16 -1 (-2800 -50)(-2550 -50);
WIRE 16 -1 (-2800 0)(-2800 -50);
WIRE 16 -1 (-2800 -50)(-2800 -100);
WIRE 16 -1 (-2800 -100)(-2550 -100);
WIRE 16 -1 (-2800 -100)(-2800 -150);
WIRE 16 -1 (-2800 -150)(-2550 -150);
WIRE 16 -1 (100 3750)(-150 3750);
WIRE 16 -1 (100 3700)(-150 3700);
WIRE 16 -1 (100 3750)(100 3700);
WIRE 16 -1 (100 3650)(-150 3650);
WIRE 16 -1 (100 3700)(100 3650);
WIRE 16 -1 (100 3600)(-150 3600);
WIRE 16 -1 (100 3650)(100 3600);
WIRE 16 -1 (-150 3550)(100 3550);
WIRE 16 -1 (100 3550)(100 3600);
WIRE 16 -1 (100 3500)(-150 3500);
WIRE 16 -1 (100 3500)(100 3550);
WIRE 16 -1 (100 3450)(-150 3450);
WIRE 16 -1 (100 3500)(100 3450);
WIRE 16 -1 (100 3400)(-150 3400);
WIRE 16 -1 (100 3450)(100 3400);
WIRE 16 -1 (100 3350)(-150 3350);
WIRE 16 -1 (100 3400)(100 3350);
WIRE 16 -1 (100 3300)(-150 3300);
WIRE 16 -1 (100 3350)(100 3300);
WIRE 16 -1 (100 3250)(-150 3250);
WIRE 16 -1 (100 3300)(100 3250);
WIRE 16 -1 (100 3200)(-150 3200);
WIRE 16 -1 (100 3250)(100 3200);
WIRE 16 -1 (100 3150)(-150 3150);
WIRE 16 -1 (100 3200)(100 3150);
WIRE 16 -1 (100 3100)(-150 3100);
WIRE 16 -1 (100 3150)(100 3100);
WIRE 16 -1 (-150 3050)(100 3050);
WIRE 16 -1 (100 3100)(100 3050);
WIRE 16 -1 (-150 3000)(100 3000);
WIRE 16 -1 (100 3050)(100 3000);
WIRE 16 -1 (-150 2950)(100 2950);
WIRE 16 -1 (100 3000)(100 2950);
WIRE 16 -1 (-150 2900)(100 2900);
WIRE 16 -1 (100 2950)(100 2900);
WIRE 16 -1 (-150 2850)(100 2850);
WIRE 16 -1 (100 2900)(100 2850);
WIRE 16 -1 (-150 2800)(100 2800);
WIRE 16 -1 (100 2850)(100 2800);
WIRE 16 -1 (-150 2750)(100 2750);
WIRE 16 -1 (100 2800)(100 2750);
WIRE 16 -1 (-150 2700)(100 2700);
WIRE 16 -1 (100 2700)(100 2750);
WIRE 16 -1 (-150 2650)(100 2650);
WIRE 16 -1 (100 2700)(100 2650);
WIRE 16 -1 (100 2600)(-150 2600);
WIRE 16 -1 (100 2650)(100 2600);
WIRE 16 -1 (100 2550)(-150 2550);
WIRE 16 -1 (100 2600)(100 2550);
WIRE 16 -1 (100 2500)(-150 2500);
WIRE 16 -1 (100 2550)(100 2500);
WIRE 16 -1 (100 2450)(-150 2450);
WIRE 16 -1 (100 2500)(100 2450);
WIRE 16 -1 (-150 2400)(100 2400);
WIRE 16 -1 (100 2400)(100 2450);
WIRE 16 -1 (100 2350)(-150 2350);
WIRE 16 -1 (100 2350)(100 2400);
WIRE 16 -1 (100 2300)(-150 2300);
WIRE 16 -1 (100 2350)(100 2300);
WIRE 16 -1 (100 2250)(-150 2250);
WIRE 16 -1 (100 2300)(100 2250);
WIRE 16 -1 (100 2200)(-150 2200);
WIRE 16 -1 (100 2250)(100 2200);
WIRE 16 -1 (100 2150)(-150 2150);
WIRE 16 -1 (100 2200)(100 2150);
WIRE 16 -1 (100 2100)(-150 2100);
WIRE 16 -1 (100 2150)(100 2100);
WIRE 16 -1 (100 2050)(-150 2050);
WIRE 16 -1 (100 2100)(100 2050);
WIRE 16 -1 (100 2000)(-150 2000);
WIRE 16 -1 (100 2050)(100 2000);
WIRE 16 -1 (100 1950)(-150 1950);
WIRE 16 -1 (100 2000)(100 1950);
WIRE 16 -1 (-150 1900)(100 1900);
WIRE 16 -1 (100 1950)(100 1900);
WIRE 16 -1 (-150 1850)(100 1850);
WIRE 16 -1 (100 1900)(100 1850);
WIRE 16 -1 (-150 1800)(100 1800);
WIRE 16 -1 (100 1850)(100 1800);
WIRE 16 -1 (-150 1750)(100 1750);
WIRE 16 -1 (100 1800)(100 1750);
WIRE 16 -1 (-150 1700)(100 1700);
WIRE 16 -1 (100 1750)(100 1700);
WIRE 16 -1 (-150 1650)(100 1650);
WIRE 16 -1 (100 1700)(100 1650);
WIRE 16 -1 (-150 1600)(100 1600);
WIRE 16 -1 (100 1650)(100 1600);
WIRE 16 -1 (-150 1550)(100 1550);
WIRE 16 -1 (100 1550)(100 1600);
WIRE 16 -1 (-150 1500)(100 1500);
WIRE 16 -1 (100 1550)(100 1500);
WIRE 16 -1 (100 1450)(-150 1450);
WIRE 16 -1 (100 1500)(100 1450);
WIRE 16 -1 (100 1400)(-150 1400);
WIRE 16 -1 (100 1450)(100 1400);
WIRE 16 -1 (100 1350)(-150 1350);
WIRE 16 -1 (100 1400)(100 1350);
WIRE 16 -1 (100 1300)(-150 1300);
WIRE 16 -1 (100 1350)(100 1300);
WIRE 16 -1 (-150 1250)(100 1250);
WIRE 16 -1 (100 1250)(100 1300);
WIRE 16 -1 (100 1200)(-150 1200);
WIRE 16 -1 (100 1200)(100 1250);
WIRE 16 -1 (100 1150)(-150 1150);
WIRE 16 -1 (100 1200)(100 1150);
WIRE 16 -1 (100 1100)(-150 1100);
WIRE 16 -1 (100 1150)(100 1100);
WIRE 16 -1 (-150 1050)(100 1050);
WIRE 16 -1 (100 1100)(100 1050);
WIRE 16 -1 (-150 1000)(100 1000);
WIRE 16 -1 (100 1050)(100 1000);
WIRE 16 -1 (-150 950)(100 950);
WIRE 16 -1 (100 1000)(100 950);
WIRE 16 -1 (-150 900)(100 900);
WIRE 16 -1 (100 950)(100 900);
WIRE 16 -1 (-150 850)(100 850);
WIRE 16 -1 (100 900)(100 850);
WIRE 16 -1 (-150 800)(100 800);
WIRE 16 -1 (100 850)(100 800);
WIRE 16 -1 (-150 750)(100 750);
WIRE 16 -1 (100 800)(100 750);
WIRE 16 -1 (-150 700)(100 700);
WIRE 16 -1 (100 700)(100 750);
WIRE 16 -1 (-150 650)(100 650);
WIRE 16 -1 (100 700)(100 650);
WIRE 16 -1 (100 600)(-150 600);
WIRE 16 -1 (100 650)(100 600);
WIRE 16 -1 (100 550)(-150 550);
WIRE 16 -1 (100 600)(100 550);
WIRE 16 -1 (100 500)(-150 500);
WIRE 16 -1 (100 550)(100 500);
WIRE 16 -1 (100 450)(-150 450);
WIRE 16 -1 (100 500)(100 450);
WIRE 16 -1 (-150 400)(100 400);
WIRE 16 -1 (100 400)(100 450);
WIRE 16 -1 (100 350)(-150 350);
WIRE 16 -1 (100 350)(100 400);
WIRE 16 -1 (100 300)(-150 300);
WIRE 16 -1 (100 350)(100 300);
WIRE 16 -1 (100 250)(-150 250);
WIRE 16 -1 (100 300)(100 250);
WIRE 16 -1 (-150 200)(100 200);
WIRE 16 -1 (100 250)(100 200);
WIRE 16 -1 (-150 150)(100 150);
WIRE 16 -1 (100 200)(100 150);
WIRE 16 -1 (-150 100)(100 100);
WIRE 16 -1 (100 150)(100 100);
WIRE 16 -1 (-150 50)(100 50);
WIRE 16 -1 (100 100)(100 50);
WIRE 16 -1 (-150 0)(100 0);
WIRE 16 -1 (100 50)(100 0);
WIRE 16 -1 (-150 -50)(100 -50);
WIRE 16 -1 (100 0)(100 -50);
WIRE 16 -1 (-150 -100)(100 -100);
WIRE 16 -1 (100 -50)(100 -100);
WIRE 16 -1 (100 -150)(100 -100);
WIRE 16 -1 (-150 -150)(100 -150);
WIRE 16 -1 (500 3750)(250 3750);
WIRE 16 -1 (250 3750)(250 3700);
WIRE 16 -1 (500 3700)(250 3700);
WIRE 16 -1 (250 3700)(250 3650);
WIRE 16 -1 (500 3650)(250 3650);
WIRE 16 -1 (250 3650)(250 3600);
WIRE 16 -1 (500 3600)(250 3600);
WIRE 16 -1 (500 3550)(250 3550);
WIRE 16 -1 (250 3600)(250 3550);
WIRE 16 -1 (250 3550)(250 3500);
WIRE 16 -1 (500 3500)(250 3500);
WIRE 16 -1 (250 3500)(250 3450);
WIRE 16 -1 (500 3450)(250 3450);
WIRE 16 -1 (250 3450)(250 3400);
WIRE 16 -1 (500 3400)(250 3400);
WIRE 16 -1 (250 3400)(250 3350);
WIRE 16 -1 (500 3350)(250 3350);
WIRE 16 -1 (250 3350)(250 3300);
WIRE 16 -1 (500 3300)(250 3300);
WIRE 16 -1 (250 3300)(250 3250);
WIRE 16 -1 (500 3250)(250 3250);
WIRE 16 -1 (250 3250)(250 3200);
WIRE 16 -1 (500 3200)(250 3200);
WIRE 16 -1 (250 3200)(250 3150);
WIRE 16 -1 (500 3150)(250 3150);
WIRE 16 -1 (250 3150)(250 3100);
WIRE 16 -1 (500 3100)(250 3100);
WIRE 16 -1 (250 3050)(500 3050);
WIRE 16 -1 (250 3100)(250 3050);
WIRE 16 -1 (250 3050)(250 3000);
WIRE 16 -1 (250 3000)(500 3000);
WIRE 16 -1 (250 3000)(250 2950);
WIRE 16 -1 (250 2950)(500 2950);
WIRE 16 -1 (250 2950)(250 2900);
WIRE 16 -1 (250 2900)(500 2900);
WIRE 16 -1 (250 2900)(250 2850);
WIRE 16 -1 (250 2850)(500 2850);
WIRE 16 -1 (250 2850)(250 2800);
WIRE 16 -1 (250 2800)(500 2800);
WIRE 16 -1 (250 2800)(250 2750);
WIRE 16 -1 (250 2750)(500 2750);
WIRE 16 -1 (250 2750)(250 2700);
WIRE 16 -1 (250 2700)(500 2700);
WIRE 16 -1 (250 2700)(250 2650);
WIRE 16 -1 (250 2650)(500 2650);
WIRE 16 -1 (250 2650)(250 2600);
WIRE 16 -1 (250 2600)(500 2600);
WIRE 16 -1 (250 2550)(500 2550);
WIRE 16 -1 (250 2600)(250 2550);
WIRE 16 -1 (250 2550)(250 2500);
WIRE 16 -1 (250 2500)(500 2500);
WIRE 16 -1 (250 2500)(250 2450);
WIRE 16 -1 (250 2450)(500 2450);
WIRE 16 -1 (250 2450)(250 2400);
WIRE 16 -1 (250 2400)(500 2400);
WIRE 16 -1 (250 2400)(250 2350);
WIRE 16 -1 (250 2350)(500 2350);
WIRE 16 -1 (250 2350)(250 2300);
WIRE 16 -1 (250 2300)(500 2300);
WIRE 16 -1 (250 2300)(250 2250);
WIRE 16 -1 (250 2250)(500 2250);
WIRE 16 -1 (250 2250)(250 2200);
WIRE 16 -1 (250 2200)(500 2200);
WIRE 16 -1 (250 2200)(250 2150);
WIRE 16 -1 (250 2150)(500 2150);
WIRE 16 -1 (250 2150)(250 2100);
WIRE 16 -1 (250 2100)(500 2100);
WIRE 16 -1 (250 2100)(250 2050);
WIRE 16 -1 (250 2050)(500 2050);
WIRE 16 -1 (250 2000)(500 2000);
WIRE 16 -1 (250 2050)(250 2000);
WIRE 16 -1 (250 2000)(250 1950);
WIRE 16 -1 (250 1950)(500 1950);
WIRE 16 -1 (250 1950)(250 1900);
WIRE 16 -1 (250 1900)(500 1900);
WIRE 16 -1 (250 1900)(250 1850);
WIRE 16 -1 (250 1850)(500 1850);
WIRE 16 -1 (250 1850)(250 1800);
WIRE 16 -1 (250 1800)(500 1800);
WIRE 16 -1 (250 1800)(250 1750);
WIRE 16 -1 (250 1750)(500 1750);
WIRE 16 -1 (250 1750)(250 1700);
WIRE 16 -1 (500 1700)(250 1700);
WIRE 16 -1 (250 1700)(250 1650);
WIRE 16 -1 (250 1650)(500 1650);
WIRE 16 -1 (250 1650)(250 1600);
WIRE 16 -1 (250 1600)(500 1600);
WIRE 16 -1 (250 1600)(250 1550);
WIRE 16 -1 (250 1550)(500 1550);
WIRE 16 -1 (250 1500)(500 1500);
WIRE 16 -1 (250 1550)(250 1500);
WIRE 16 -1 (250 1500)(250 1450);
WIRE 16 -1 (250 1450)(500 1450);
WIRE 16 -1 (250 1450)(250 1400);
WIRE 16 -1 (250 1400)(500 1400);
WIRE 16 -1 (250 1400)(250 1350);
WIRE 16 -1 (250 1350)(500 1350);
WIRE 16 -1 (250 1350)(250 1300);
WIRE 16 -1 (250 1300)(500 1300);
WIRE 16 -1 (250 1300)(250 1250);
WIRE 16 -1 (250 1250)(500 1250);
WIRE 16 -1 (250 1250)(250 1200);
WIRE 16 -1 (250 1200)(500 1200);
WIRE 16 -1 (250 1200)(250 1150);
WIRE 16 -1 (250 1150)(500 1150);
WIRE 16 -1 (250 1150)(250 1100);
WIRE 16 -1 (250 1100)(500 1100);
WIRE 16 -1 (250 1100)(250 1050);
WIRE 16 -1 (250 1050)(500 1050);
WIRE 16 -1 (250 1000)(500 1000);
WIRE 16 -1 (250 1050)(250 1000);
WIRE 16 -1 (250 1000)(250 950);
WIRE 16 -1 (250 950)(500 950);
WIRE 16 -1 (250 950)(250 900);
WIRE 16 -1 (250 900)(500 900);
WIRE 16 -1 (250 900)(250 850);
WIRE 16 -1 (250 850)(500 850);
WIRE 16 -1 (250 850)(250 800);
WIRE 16 -1 (250 800)(500 800);
WIRE 16 -1 (250 800)(250 750);
WIRE 16 -1 (250 750)(500 750);
WIRE 16 -1 (250 750)(250 700);
WIRE 16 -1 (500 700)(250 700);
WIRE 16 -1 (250 700)(250 650);
WIRE 16 -1 (250 650)(500 650);
WIRE 16 -1 (250 650)(250 600);
WIRE 16 -1 (250 600)(500 600);
WIRE 16 -1 (250 600)(250 550);
WIRE 16 -1 (250 550)(500 550);
WIRE 16 -1 (250 500)(500 500);
WIRE 16 -1 (250 550)(250 500);
WIRE 16 -1 (250 500)(250 450);
WIRE 16 -1 (250 450)(500 450);
WIRE 16 -1 (250 450)(250 400);
WIRE 16 -1 (500 400)(250 400);
WIRE 16 -1 (250 400)(250 350);
WIRE 16 -1 (250 350)(500 350);
WIRE 16 -1 (250 350)(250 300);
WIRE 16 -1 (250 300)(500 300);
WIRE 16 -1 (250 300)(250 250);
WIRE 16 -1 (250 250)(500 250);
WIRE 16 -1 (250 250)(250 200);
WIRE 16 -1 (250 200)(500 200);
WIRE 16 -1 (250 200)(250 150);
WIRE 16 -1 (250 150)(500 150);
WIRE 16 -1 (250 150)(250 100);
WIRE 16 -1 (250 100)(500 100);
WIRE 16 -1 (250 100)(250 50);
WIRE 16 -1 (500 50)(250 50);
WIRE 16 -1 (250 50)(250 0);
WIRE 16 -1 (250 0)(500 0);
WIRE 16 -1 (250 -50)(500 -50);
WIRE 16 -1 (250 0)(250 -50);
WIRE 16 -1 (250 -50)(250 -100);
WIRE 16 -1 (250 -100)(500 -100);
WIRE 16 -1 (250 -100)(250 -150);
WIRE 16 -1 (250 -150)(500 -150);
WIRE 16 -1 (6175 3750)(5925 3750);
WIRE 16 -1 (6175 3700)(5925 3700);
WIRE 16 -1 (6175 3750)(6175 3700);
WIRE 16 -1 (6175 3650)(5925 3650);
WIRE 16 -1 (6175 3700)(6175 3650);
WIRE 16 -1 (6175 3600)(5925 3600);
WIRE 16 -1 (6175 3650)(6175 3600);
WIRE 16 -1 (5925 3550)(6175 3550);
WIRE 16 -1 (6175 3550)(6175 3600);
WIRE 16 -1 (6175 3500)(5925 3500);
WIRE 16 -1 (6175 3500)(6175 3550);
WIRE 16 -1 (6175 3450)(5925 3450);
WIRE 16 -1 (6175 3500)(6175 3450);
WIRE 16 -1 (6175 3400)(5925 3400);
WIRE 16 -1 (6175 3450)(6175 3400);
WIRE 16 -1 (6175 3350)(5925 3350);
WIRE 16 -1 (6175 3400)(6175 3350);
WIRE 16 -1 (6175 3300)(5925 3300);
WIRE 16 -1 (6175 3350)(6175 3300);
WIRE 16 -1 (6175 3250)(5925 3250);
WIRE 16 -1 (6175 3300)(6175 3250);
WIRE 16 -1 (6175 3200)(5925 3200);
WIRE 16 -1 (6175 3250)(6175 3200);
WIRE 16 -1 (6175 3150)(5925 3150);
WIRE 16 -1 (6175 3200)(6175 3150);
WIRE 16 -1 (6175 3100)(5925 3100);
WIRE 16 -1 (6175 3150)(6175 3100);
WIRE 16 -1 (5925 3050)(6175 3050);
WIRE 16 -1 (6175 3100)(6175 3050);
WIRE 16 -1 (5925 3000)(6175 3000);
WIRE 16 -1 (6175 3050)(6175 3000);
WIRE 16 -1 (5925 2950)(6175 2950);
WIRE 16 -1 (6175 3000)(6175 2950);
WIRE 16 -1 (5925 2900)(6175 2900);
WIRE 16 -1 (6175 2950)(6175 2900);
WIRE 16 -1 (5925 2850)(6175 2850);
WIRE 16 -1 (6175 2900)(6175 2850);
WIRE 16 -1 (5925 2800)(6175 2800);
WIRE 16 -1 (6175 2850)(6175 2800);
WIRE 16 -1 (5925 2750)(6175 2750);
WIRE 16 -1 (6175 2800)(6175 2750);
WIRE 16 -1 (5925 2700)(6175 2700);
WIRE 16 -1 (6175 2700)(6175 2750);
WIRE 16 -1 (5925 2650)(6175 2650);
WIRE 16 -1 (6175 2700)(6175 2650);
WIRE 16 -1 (6175 2600)(5925 2600);
WIRE 16 -1 (6175 2650)(6175 2600);
WIRE 16 -1 (6175 2550)(5925 2550);
WIRE 16 -1 (6175 2600)(6175 2550);
WIRE 16 -1 (6175 2500)(5925 2500);
WIRE 16 -1 (6175 2550)(6175 2500);
WIRE 16 -1 (6175 2450)(5925 2450);
WIRE 16 -1 (6175 2500)(6175 2450);
WIRE 16 -1 (5925 2400)(6175 2400);
WIRE 16 -1 (6175 2400)(6175 2450);
WIRE 16 -1 (6175 2350)(5925 2350);
WIRE 16 -1 (6175 2350)(6175 2400);
WIRE 16 -1 (6175 2300)(5925 2300);
WIRE 16 -1 (6175 2350)(6175 2300);
WIRE 16 -1 (6175 2250)(5925 2250);
WIRE 16 -1 (6175 2300)(6175 2250);
WIRE 16 -1 (6175 2200)(5925 2200);
WIRE 16 -1 (6175 2250)(6175 2200);
WIRE 16 -1 (6175 2150)(5925 2150);
WIRE 16 -1 (6175 2200)(6175 2150);
WIRE 16 -1 (6175 2100)(5925 2100);
WIRE 16 -1 (6175 2150)(6175 2100);
WIRE 16 -1 (6175 2050)(5925 2050);
WIRE 16 -1 (6175 2100)(6175 2050);
WIRE 16 -1 (6175 2000)(5925 2000);
WIRE 16 -1 (6175 2050)(6175 2000);
WIRE 16 -1 (6175 1950)(5925 1950);
WIRE 16 -1 (6175 2000)(6175 1950);
WIRE 16 -1 (5925 1900)(6175 1900);
WIRE 16 -1 (6175 1950)(6175 1900);
WIRE 16 -1 (5925 1850)(6175 1850);
WIRE 16 -1 (6175 1900)(6175 1850);
WIRE 16 -1 (5925 1800)(6175 1800);
WIRE 16 -1 (6175 1850)(6175 1800);
WIRE 16 -1 (5925 1750)(6175 1750);
WIRE 16 -1 (6175 1800)(6175 1750);
WIRE 16 -1 (5925 1700)(6175 1700);
WIRE 16 -1 (6175 1750)(6175 1700);
WIRE 16 -1 (5925 1650)(6175 1650);
WIRE 16 -1 (6175 1700)(6175 1650);
WIRE 16 -1 (5925 1600)(6175 1600);
WIRE 16 -1 (6175 1650)(6175 1600);
WIRE 16 -1 (5925 1550)(6175 1550);
WIRE 16 -1 (6175 1550)(6175 1600);
WIRE 16 -1 (5925 1500)(6175 1500);
WIRE 16 -1 (6175 1550)(6175 1500);
WIRE 16 -1 (6175 1450)(5925 1450);
WIRE 16 -1 (6175 1500)(6175 1450);
WIRE 16 -1 (6175 1400)(5925 1400);
WIRE 16 -1 (6175 1450)(6175 1400);
WIRE 16 -1 (6175 1350)(5925 1350);
WIRE 16 -1 (6175 1400)(6175 1350);
WIRE 16 -1 (6175 1300)(5925 1300);
WIRE 16 -1 (6175 1350)(6175 1300);
WIRE 16 -1 (5925 1250)(6175 1250);
WIRE 16 -1 (6175 1250)(6175 1300);
WIRE 16 -1 (6175 1200)(5925 1200);
WIRE 16 -1 (6175 1200)(6175 1250);
WIRE 16 -1 (6175 1150)(5925 1150);
WIRE 16 -1 (6175 1200)(6175 1150);
WIRE 16 -1 (6175 1100)(5925 1100);
WIRE 16 -1 (6175 1150)(6175 1100);
WIRE 16 -1 (5925 1050)(6175 1050);
WIRE 16 -1 (6175 1100)(6175 1050);
WIRE 16 -1 (5925 1000)(6175 1000);
WIRE 16 -1 (6175 1050)(6175 1000);
WIRE 16 -1 (5925 950)(6175 950);
WIRE 16 -1 (6175 1000)(6175 950);
WIRE 16 -1 (5925 900)(6175 900);
WIRE 16 -1 (6175 950)(6175 900);
WIRE 16 -1 (5925 850)(6175 850);
WIRE 16 -1 (6175 900)(6175 850);
WIRE 16 -1 (5925 800)(6175 800);
WIRE 16 -1 (6175 850)(6175 800);
WIRE 16 -1 (5925 750)(6175 750);
WIRE 16 -1 (6175 800)(6175 750);
WIRE 16 -1 (5925 700)(6175 700);
WIRE 16 -1 (6175 700)(6175 750);
WIRE 16 -1 (5925 650)(6175 650);
WIRE 16 -1 (6175 700)(6175 650);
WIRE 16 -1 (6175 600)(5925 600);
WIRE 16 -1 (6175 650)(6175 600);
WIRE 16 -1 (6175 550)(5925 550);
WIRE 16 -1 (6175 600)(6175 550);
WIRE 16 -1 (6175 500)(5925 500);
WIRE 16 -1 (6175 550)(6175 500);
WIRE 16 -1 (6175 450)(5925 450);
WIRE 16 -1 (6175 500)(6175 450);
WIRE 16 -1 (5925 400)(6175 400);
WIRE 16 -1 (6175 400)(6175 450);
WIRE 16 -1 (6175 350)(5925 350);
WIRE 16 -1 (6175 350)(6175 400);
WIRE 16 -1 (6175 300)(5925 300);
WIRE 16 -1 (6175 350)(6175 300);
WIRE 16 -1 (6175 250)(5925 250);
WIRE 16 -1 (6175 300)(6175 250);
WIRE 16 -1 (5925 200)(6175 200);
WIRE 16 -1 (6175 250)(6175 200);
WIRE 16 -1 (5925 150)(6175 150);
WIRE 16 -1 (6175 200)(6175 150);
WIRE 16 -1 (5925 100)(6175 100);
WIRE 16 -1 (6175 150)(6175 100);
WIRE 16 -1 (5925 50)(6175 50);
WIRE 16 -1 (6175 100)(6175 50);
WIRE 16 -1 (6175 50)(6175 0);
WIRE 16 -1 (5925 0)(6175 0);
WIRE 16 -1 (5925 -50)(6175 -50);
WIRE 16 -1 (6175 0)(6175 -50);
WIRE 16 -1 (5925 -100)(6175 -100);
WIRE 16 -1 (6175 -50)(6175 -100);
WIRE 16 -1 (6175 -150)(6175 -100);
WIRE 16 -1 (5925 -150)(6175 -150);
DOT 1 (100 2850);
DOT 1 (250 2850);
DOT 1 (6175 3700);
DOT 1 (6175 3600);
DOT 1 (6175 3650);
DOT 1 (6175 3550);
DOT 1 (6175 3450);
DOT 1 (6175 3500);
DOT 1 (6175 3300);
DOT 1 (6175 3350);
DOT 1 (6175 3400);
DOT 1 (6175 3200);
DOT 1 (6175 3250);
DOT 1 (6175 3050);
DOT 1 (6175 3150);
DOT 1 (6175 3100);
DOT 1 (6175 3000);
DOT 1 (6175 2950);
DOT 1 (6175 2900);
DOT 1 (6175 2800);
DOT 1 (6175 2850);
DOT 1 (6175 2750);
DOT 1 (6175 2700);
DOT 1 (6175 2650);
DOT 1 (6175 2600);
DOT 1 (6175 2550);
DOT 1 (6175 2450);
DOT 1 (6175 2500);
DOT 1 (6175 2400);
DOT 1 (6175 2350);
DOT 1 (6175 2300);
DOT 1 (6175 2200);
DOT 1 (6175 2250);
DOT 1 (6175 2150);
DOT 1 (6175 2100);
DOT 1 (6175 2050);
DOT 1 (6175 1950);
DOT 1 (6175 2000);
DOT 1 (6175 1900);
DOT 1 (6175 1800);
DOT 1 (6175 1850);
DOT 1 (6175 1750);
DOT 1 (6175 1700);
DOT 1 (6175 1650);
DOT 1 (6175 1600);
DOT 1 (6175 1550);
DOT 1 (6175 1500);
DOT 1 (6175 1400);
DOT 1 (6175 1450);
DOT 1 (6175 1250);
DOT 1 (6175 1300);
DOT 1 (6175 1350);
DOT 1 (6175 1150);
DOT 1 (6175 1200);
DOT 1 (6175 1000);
DOT 1 (6175 1100);
DOT 1 (6175 1050);
DOT 1 (6175 950);
DOT 1 (6175 900);
DOT 1 (6175 850);
DOT 1 (6175 750);
DOT 1 (6175 800);
DOT 1 (6175 650);
DOT 1 (6175 700);
DOT 1 (6175 600);
DOT 1 (6175 500);
DOT 1 (6175 550);
DOT 1 (6175 450);
DOT 1 (6175 400);
DOT 1 (6175 350);
DOT 1 (6175 250);
DOT 1 (6175 300);
DOT 1 (6175 200);
DOT 1 (6175 150);
DOT 1 (6175 100);
DOT 1 (6175 50);
DOT 1 (6175 0);
DOT 1 (6175 -100);
DOT 1 (6175 -50);
DOT 1 (6175 -150);
DOT 1 (3275 3700);
DOT 1 (3275 3650);
DOT 1 (3275 3600);
DOT 1 (3275 3550);
DOT 1 (3275 3450);
DOT 1 (3275 3500);
DOT 1 (3150 3700);
DOT 1 (3150 3650);
DOT 1 (3150 3600);
DOT 1 (3150 3550);
DOT 1 (3150 3450);
DOT 1 (3150 3500);
DOT 1 (3275 3400);
DOT 1 (3275 3350);
DOT 1 (3275 3300);
DOT 1 (3275 3250);
DOT 1 (3275 3200);
DOT 1 (3275 3150);
DOT 1 (3275 3100);
DOT 1 (3275 3050);
DOT 1 (3275 3000);
DOT 1 (3275 2950);
DOT 1 (3150 3400);
DOT 1 (3150 3350);
DOT 1 (3150 3300);
DOT 1 (3150 3250);
DOT 1 (3150 3200);
DOT 1 (3150 3150);
DOT 1 (3150 3100);
DOT 1 (3150 3050);
DOT 1 (3150 3000);
DOT 1 (3150 2950);
DOT 1 (3275 2900);
DOT 1 (3150 2900);
DOT 1 (3275 2850);
DOT 1 (3275 2800);
DOT 1 (3275 2750);
DOT 1 (3275 2700);
DOT 1 (3275 2650);
DOT 1 (3275 2600);
DOT 1 (3275 2550);
DOT 1 (3275 2500);
DOT 1 (3275 2450);
DOT 1 (3275 2400);
DOT 1 (3150 2850);
DOT 1 (3150 2800);
DOT 1 (3150 2750);
DOT 1 (3150 2700);
DOT 1 (3150 2650);
DOT 1 (3150 2600);
DOT 1 (3150 2550);
DOT 1 (3150 2500);
DOT 1 (3150 2450);
DOT 1 (3150 2400);
DOT 1 (3275 2350);
DOT 1 (3275 2300);
DOT 1 (3275 2250);
DOT 1 (3275 2200);
DOT 1 (3275 2150);
DOT 1 (3275 2100);
DOT 1 (3275 2050);
DOT 1 (3275 2000);
DOT 1 (3275 1950);
DOT 1 (3275 1900);
DOT 1 (3150 2350);
DOT 1 (3150 2300);
DOT 1 (3150 2250);
DOT 1 (3150 2200);
DOT 1 (3150 2150);
DOT 1 (3150 2100);
DOT 1 (3150 2050);
DOT 1 (3150 2000);
DOT 1 (3150 1950);
DOT 1 (3150 1900);
DOT 1 (3275 1850);
DOT 1 (3275 1800);
DOT 1 (3275 1750);
DOT 1 (3275 1700);
DOT 1 (3275 1650);
DOT 1 (3275 1600);
DOT 1 (3275 1550);
DOT 1 (3275 1500);
DOT 1 (3275 1400);
DOT 1 (3275 1450);
DOT 1 (3150 1850);
DOT 1 (3150 1800);
DOT 1 (3150 1750);
DOT 1 (3150 1700);
DOT 1 (3150 1650);
DOT 1 (3150 1600);
DOT 1 (3150 1550);
DOT 1 (3150 1500);
DOT 1 (3150 1400);
DOT 1 (3150 1450);
DOT 1 (3275 1350);
DOT 1 (3275 1300);
DOT 1 (3275 1250);
DOT 1 (3275 1200);
DOT 1 (3275 1150);
DOT 1 (3275 1100);
DOT 1 (3275 1050);
DOT 1 (3275 1000);
DOT 1 (3275 950);
DOT 1 (3275 900);
DOT 1 (3150 1350);
DOT 1 (3150 1300);
DOT 1 (3150 1250);
DOT 1 (3150 1200);
DOT 1 (3150 1150);
DOT 1 (3150 1100);
DOT 1 (3150 1050);
DOT 1 (3150 1000);
DOT 1 (3150 950);
DOT 1 (3150 900);
DOT 1 (3275 850);
DOT 1 (3150 850);
DOT 1 (3275 800);
DOT 1 (3275 750);
DOT 1 (3275 700);
DOT 1 (3275 650);
DOT 1 (3275 600);
DOT 1 (3275 550);
DOT 1 (3275 500);
DOT 1 (3275 450);
DOT 1 (3275 400);
DOT 1 (3150 800);
DOT 1 (3150 750);
DOT 1 (3150 700);
DOT 1 (3150 650);
DOT 1 (3150 600);
DOT 1 (3150 550);
DOT 1 (3150 450);
DOT 1 (3150 400);
DOT 1 (3275 350);
DOT 1 (3150 350);
DOT 1 (3275 300);
DOT 1 (3275 250);
DOT 1 (3275 200);
DOT 1 (3275 150);
DOT 1 (3275 100);
DOT 1 (3275 50);
DOT 1 (3275 0);
DOT 1 (3275 -50);
DOT 1 (3275 -100);
DOT 1 (3275 -150);
DOT 1 (3150 300);
DOT 1 (3150 250);
DOT 1 (3150 200);
DOT 1 (3150 150);
DOT 1 (3150 100);
DOT 1 (3150 50);
DOT 1 (3150 0);
DOT 1 (3150 -50);
DOT 1 (3150 -100);
DOT 1 (3150 -150);
DOT 1 (6175 -200);
DOT 1 (3275 -200);
DOT 1 (3150 -200);
DOT 1 (250 3700);
DOT 1 (250 3650);
DOT 1 (250 3600);
DOT 1 (250 3550);
DOT 1 (250 3450);
DOT 1 (250 3500);
DOT 1 (100 3600);
DOT 1 (100 3650);
DOT 1 (100 3550);
DOT 1 (100 3500);
DOT 1 (100 3450);
DOT 1 (250 3400);
DOT 1 (250 3350);
DOT 1 (250 3300);
DOT 1 (250 3250);
DOT 1 (250 3200);
DOT 1 (250 3150);
DOT 1 (250 3100);
DOT 1 (250 3050);
DOT 1 (250 3000);
DOT 1 (250 2950);
DOT 1 (100 3300);
DOT 1 (100 3350);
DOT 1 (100 3400);
DOT 1 (100 3200);
DOT 1 (100 3250);
DOT 1 (100 3050);
DOT 1 (100 3150);
DOT 1 (100 3100);
DOT 1 (100 2950);
DOT 1 (100 3000);
DOT 1 (250 2900);
DOT 1 (100 2900);
DOT 1 (250 2800);
DOT 1 (250 2750);
DOT 1 (250 2700);
DOT 1 (250 2650);
DOT 1 (250 2600);
DOT 1 (250 2550);
DOT 1 (250 2500);
DOT 1 (250 2450);
DOT 1 (250 2400);
DOT 1 (100 2800);
DOT 1 (100 2700);
DOT 1 (100 2750);
DOT 1 (100 2650);
DOT 1 (100 2550);
DOT 1 (100 2600);
DOT 1 (100 2450);
DOT 1 (100 2400);
DOT 1 (100 2500);
DOT 1 (250 2350);
DOT 1 (250 2300);
DOT 1 (250 2250);
DOT 1 (250 2200);
DOT 1 (250 2150);
DOT 1 (250 2100);
DOT 1 (250 2050);
DOT 1 (250 2000);
DOT 1 (250 1950);
DOT 1 (250 1900);
DOT 1 (100 2300);
DOT 1 (100 2350);
DOT 1 (100 2150);
DOT 1 (100 2200);
DOT 1 (100 2250);
DOT 1 (100 2050);
DOT 1 (100 2100);
DOT 1 (100 2000);
DOT 1 (100 1900);
DOT 1 (100 1950);
DOT 1 (250 1850);
DOT 1 (250 1800);
DOT 1 (250 1750);
DOT 1 (250 1700);
DOT 1 (250 1650);
DOT 1 (250 1600);
DOT 1 (250 1550);
DOT 1 (250 1500);
DOT 1 (250 1400);
DOT 1 (250 1450);
DOT 1 (100 1800);
DOT 1 (100 1850);
DOT 1 (100 1750);
DOT 1 (100 1700);
DOT 1 (100 1650);
DOT 1 (100 1600);
DOT 1 (100 1550);
DOT 1 (100 1500);
DOT 1 (100 1400);
DOT 1 (100 1450);
DOT 1 (250 1350);
DOT 1 (250 1300);
DOT 1 (250 1250);
DOT 1 (250 1200);
DOT 1 (250 1150);
DOT 1 (250 1100);
DOT 1 (250 1050);
DOT 1 (250 1000);
DOT 1 (250 950);
DOT 1 (250 900);
DOT 1 (100 1250);
DOT 1 (100 1300);
DOT 1 (100 1350);
DOT 1 (100 1150);
DOT 1 (100 1200);
DOT 1 (100 1000);
DOT 1 (100 1100);
DOT 1 (100 1050);
DOT 1 (100 950);
DOT 1 (100 900);
DOT 1 (250 850);
DOT 1 (100 850);
DOT 1 (250 800);
DOT 1 (250 750);
DOT 1 (250 700);
DOT 1 (250 650);
DOT 1 (250 600);
DOT 1 (250 550);
DOT 1 (250 500);
DOT 1 (250 450);
DOT 1 (250 400);
DOT 1 (100 800);
DOT 1 (100 750);
DOT 1 (100 700);
DOT 1 (100 600);
DOT 1 (100 550);
DOT 1 (100 500);
DOT 1 (100 450);
DOT 1 (100 400);
DOT 1 (250 350);
DOT 1 (100 350);
DOT 1 (250 300);
DOT 1 (250 250);
DOT 1 (250 200);
DOT 1 (250 150);
DOT 1 (250 100);
DOT 1 (250 50);
DOT 1 (250 0);
DOT 1 (250 -50);
DOT 1 (250 -100);
DOT 1 (250 -150);
DOT 1 (100 250);
DOT 1 (100 300);
DOT 1 (100 100);
DOT 1 (100 150);
DOT 1 (100 200);
DOT 1 (100 0);
DOT 1 (100 50);
DOT 1 (100 -50);
DOT 1 (100 -150);
DOT 1 (100 -100);
DOT 1 (-2800 3700);
DOT 1 (-2800 3650);
DOT 1 (-2800 3600);
DOT 1 (-2800 3550);
DOT 1 (-2800 3500);
DOT 1 (-2800 3450);
DOT 1 (-2800 3400);
DOT 1 (-2800 3350);
DOT 1 (-2800 3300);
DOT 1 (-2800 3250);
DOT 1 (-2800 3200);
DOT 1 (-2800 3150);
DOT 1 (-2800 3100);
DOT 1 (-2800 3050);
DOT 1 (-2800 3000);
DOT 1 (-2800 2950);
DOT 1 (-2800 2900);
DOT 1 (-2800 2850);
DOT 1 (-2800 2800);
DOT 1 (-2800 2750);
DOT 1 (-2800 2700);
DOT 1 (-2800 2650);
DOT 1 (-2800 2600);
DOT 1 (-2800 2550);
DOT 1 (-2800 2500);
DOT 1 (-2800 2450);
DOT 1 (-2800 2400);
DOT 1 (-2800 2350);
DOT 1 (-2800 2300);
DOT 1 (-2800 2250);
DOT 1 (-2800 2200);
DOT 1 (-2800 2150);
DOT 1 (-2800 2100);
DOT 1 (-2800 2050);
DOT 1 (-2800 2000);
DOT 1 (-2800 1950);
DOT 1 (-2800 1900);
DOT 1 (-2800 1850);
DOT 1 (-2800 1800);
DOT 1 (-2800 1750);
DOT 1 (-2800 1700);
DOT 1 (-2800 1650);
DOT 1 (-2800 1600);
DOT 1 (-2800 1550);
DOT 1 (-2800 1500);
DOT 1 (-2800 1400);
DOT 1 (-2800 1450);
DOT 1 (-2800 1350);
DOT 1 (-2800 1300);
DOT 1 (-2800 1250);
DOT 1 (-2800 1200);
DOT 1 (-2800 1150);
DOT 1 (-2800 1100);
DOT 1 (-2800 1050);
DOT 1 (-2800 1000);
DOT 1 (-2800 950);
DOT 1 (-2800 900);
DOT 1 (-2800 850);
DOT 1 (-2800 800);
DOT 1 (-2800 750);
DOT 1 (-2800 700);
DOT 1 (-2800 650);
DOT 1 (-2800 600);
DOT 1 (-2800 550);
DOT 1 (-2800 500);
DOT 1 (-2800 450);
DOT 1 (-2800 400);
DOT 1 (-2800 350);
DOT 1 (-2800 300);
DOT 1 (-2800 250);
DOT 1 (-2800 200);
DOT 1 (-2800 100);
DOT 1 (-2800 50);
DOT 1 (-2800 0);
DOT 1 (-2800 -50);
DOT 1 (-2800 -100);
DOT 1 (-2800 -150);
DOT 1 (250 -200);
DOT 1 (100 -200);
DOT 1 (-2800 -200);
DOT 1 (100 650);
DOT 1 (-2800 150);
DOT 1 (3150 500);
DOT 1 (100 3700);
QUIT
